G04 ================== begin FILE IDENTIFICATION RECORD ==================*
G04 Layout Name:  t6mg_pdb_a_v02_0109_1330.brd*
G04 Film Name:    top.art*
G04 File Format:  Gerber RS274X*
G04 File Origin:  Cadence Allegro 16.3-S038*
G04 Origin Date:  Mon Jan 13 14:11:50 2014*
G04 *
G04 Layer:  DRAWING FORMAT/TITLE_BLOCK*
G04 Layer:  VIA CLASS/TOP*
G04 Layer:  PIN/TOP*
G04 Layer:  MANUFACTURING/PHOTOPLOT_OUTLINE*
G04 Layer:  ETCH/TOP*
G04 Layer:  DRAWING FORMAT/TITLE_DATA_TOP*
G04 *
G04 Offset:    (0.00 0.00)*
G04 Mirror:    No*
G04 Mode:      Positive*
G04 Rotation:  0*
G04 FullContactRelief:  No*
G04 UndefLineWidth:     6.00*
G04 ================== end FILE IDENTIFICATION RECORD ====================*
%FSLAX25Y25*MOIN*%
%IR0*IPPOS*OFA0.00000B0.00000*MIA0B0*SFA1.00000B1.00000*%
%ADD11C,.02*%
%ADD23C,.03*%
%ADD17C,.04*%
%ADD15C,.052*%
%ADD12C,.063*%
%ADD39C,.046*%
%ADD35C,.064*%
%ADD25C,.055*%
%ADD19R,.04X.04*%
%ADD30C,.039*%
%ADD22C,.093*%
%ADD28R,.052X.052*%
%ADD21C,.077*%
%ADD18C,.095*%
%ADD13R,.063X.063*%
%ADD38R,.046X.046*%
%ADD36R,.064X.064*%
%ADD26R,.055X.055*%
%ADD37C,.099*%
%ADD24R,.077X.077*%
%ADD42O,.205X.244*%
%ADD14R,.02X.018*%
%ADD20R,.018X.02*%
%ADD31R,.05X.035*%
%ADD34R,.032X.028*%
%ADD10C,.132*%
%ADD41C,.205*%
%ADD40R,.028X.032*%
%ADD43C,.315*%
%ADD32R,.044X.054*%
%ADD29R,.068X.022*%
%ADD16C,.126*%
%ADD33R,.022X.068*%
%ADD27C,.158*%
%ADD44C,.022*%
%ADD45C,.026*%
%ADD46C,.018*%
%ADD47C,.006*%
%ADD61C,.03004*%
%ADD62C,.05004*%
%ADD54C,.06204*%
%ADD52C,.07304*%
%ADD74C,.05604*%
%ADD73C,.07404*%
%ADD57C,.06504*%
%ADD71C,.08704*%
%ADD51C,.08407*%
%ADD67C,.08409*%
%ADD56C,.10304*%
%ADD55C,.10504*%
%ADD48C,.63006*%
%ADD59R,.06204X.06204*%
%ADD70C,.12806*%
%ADD49C,.16406*%
%ADD78C,.198*%
%ADD76R,.06502X.06502*%
%ADD69C,.13266*%
%ADD75R,.06504X.06502*%
%ADD66C,.28352*%
%ADD63R,.05602X.05604*%
%ADD60R,.07804X.03204*%
%ADD58R,.06502X.06504*%
%ADD53R,.07304X.07304*%
%ADD50C,.15806*%
%ADD77R,.06504X.06504*%
%ADD64R,.05604X.05604*%
%ADD72R,.08704X.08702*%
%ADD65O,.28352X.32289*%
%ADD68C,.39377*%
G75*
%LPD*%
G75*
G36*
G01X104331Y2004D02*
G02X100429Y5906I0J3902D01*
G01Y9843D01*
G03X92520Y17752I-7909J0D01*
G01X5906D01*
G02X2004Y21654I0J3902D01*
G01Y2064961D01*
G02X5905Y2068862I3901J0D01*
G01X92520D01*
G03X100429Y2076772I0J7909D01*
G01Y2080709D01*
G02X104331Y2084610I3902J-1D01*
G01X397638D01*
G02X403508Y2078740I0J-5870D01*
G01Y7874D01*
G02X397638Y2004I-5870J0D01*
G01X104331D01*
G37*
%LPC*%
G75*
G36*
G01X104331Y3997D02*
X104330D01*
G02X102422Y5906I0J1908D01*
G01Y9843D01*
G03X92520Y19745I-9903J-1D01*
G01X91602D01*
Y19746D01*
X5906D01*
Y19745D01*
X5905D01*
G02X3998Y21711I1J1908D01*
G01Y2064961D01*
G02X4556Y2066310I1908J1D01*
G02X5964Y2066868I1349J-1349D01*
G01X92520D01*
G03X99522Y2069769I-1J9903D01*
G03X102422Y2076772I-7003J7002D01*
G01Y2080709D01*
G02X104330Y2082617I1908J0D01*
G01X104331D01*
Y2082616D01*
X397638D01*
G02X401514Y2078740I0J-3876D01*
G01Y1915551D01*
X401515Y1915541D01*
Y1915529D01*
X401514D01*
Y7874D01*
G02X397638Y3998I-3876J0D01*
G01X104331D01*
Y3997D01*
G37*
%LPD*%
G75*
G36*
G01X5875Y20748D02*
G02X5000Y21604I30J906D01*
G01Y139130D01*
G02X6707Y139837I1000J0D01*
G01X19104Y127440D01*
Y121978D01*
X26408D01*
Y129280D01*
X20945D01*
X6608Y143618D01*
Y696078D01*
X15388Y704859D01*
X15590Y704862D01*
G03X18030Y707675I-43J2502D01*
G03X18024Y707718I-2482J-324D01*
G02X18165Y708141I495J70D01*
G01X19014Y708990D01*
X26230D01*
X29498Y705722D01*
X78192D01*
X78241Y705771D01*
X79265D01*
X79553Y705502D01*
X79566Y705304D01*
G03X79808Y704475I1997J133D01*
G02X78931Y702994I-877J-481D01*
G01X78768D01*
Y701932D01*
X76526Y699691D01*
Y693036D01*
X75802Y692312D01*
X68278D01*
Y689108D01*
X76082D01*
Y689116D01*
X76374Y689408D01*
X76580D01*
X79130Y691958D01*
Y698613D01*
X80708Y700192D01*
X81770D01*
Y700292D01*
X82531D01*
G02X83031Y699792I0J-500D01*
G01Y697041D01*
X86035D01*
Y697142D01*
X87180D01*
Y697042D01*
X87380Y696842D01*
Y696182D01*
X89543Y694019D01*
G02X89078Y692341I-707J-707D01*
G01Y689108D01*
X96882D01*
Y689116D01*
X97174Y689408D01*
X98859D01*
G02X99206Y689269I1J-500D01*
G03X102036Y692099I1389J1441D01*
G02X101896Y692446I360J347D01*
G01Y693612D01*
X101844Y693876D01*
X101910Y694035D01*
G02X102372Y694344I462J-191D01*
G01X104947D01*
X105838Y693454D01*
Y446616D01*
X85948Y426726D01*
Y412181D01*
X87637Y410491D01*
X89028Y409100D01*
Y389208D01*
X91297Y386939D01*
X94053Y384184D01*
X94321D01*
G02X95016Y382496I-32J-1000D01*
G01X91158Y378638D01*
Y369415D01*
X93871Y366702D01*
X106477D01*
X114081Y359098D01*
G02Y358418I-368J-340D01*
G01X111118Y355455D01*
Y89774D01*
G02X110618Y89296I-500J23D01*
G01X105693D01*
X99180Y82783D01*
Y74832D01*
X90024Y65676D01*
X90008Y65661D01*
Y24204D01*
X86552Y20748D01*
X49509D01*
G03X49483I-13J-1502D01*
G01X5875D01*
G37*
G36*
G01X83352Y777577D02*
Y726333D01*
X66753Y709734D01*
X32256D01*
X28668Y713322D01*
X15058D01*
X13486Y711750D01*
G02X11778Y712457I-708J707D01*
G01Y716910D01*
X10207Y718481D01*
X10133Y718704D01*
X10150Y718821D01*
G03X6477Y721373I-2477J354D01*
G02X5000Y722251I-477J878D01*
G01Y723973D01*
G02X6477Y724851I1000J0D01*
G03Y729247I1196J2198D01*
G02X5000Y730125I-477J878D01*
G01Y731847D01*
G02X6477Y732725I1000J0D01*
G03Y737121I1196J2198D01*
G02X5000Y737999I-477J878D01*
G01Y739721D01*
G02X6477Y740599I1000J0D01*
G03Y744995I1196J2198D01*
G02X5000Y745873I-477J878D01*
G01Y747595D01*
G02X6477Y748473I1000J0D01*
G03Y752869I1196J2198D01*
G02X5000Y753747I-477J878D01*
G01Y755469D01*
G02X6477Y756347I1000J0D01*
G03Y760743I1196J2198D01*
G02X5000Y761621I-477J878D01*
G01Y763343D01*
G02X6477Y764221I1000J0D01*
G03Y768617I1196J2198D01*
G02X5000Y769495I-477J878D01*
G01Y771217D01*
G02X6477Y772095I1000J0D01*
G03Y776491I1196J2198D01*
G02X5000Y777369I-477J878D01*
G01Y779091D01*
G02X6477Y779969I1000J0D01*
G03Y784365I1196J2198D01*
G02X5000Y785243I-477J878D01*
G01Y786965D01*
G02X6477Y787843I1000J0D01*
G03X8964Y792185I1196J2198D01*
G01X9002Y792222D01*
Y794061D01*
X10026Y795085D01*
X13528Y798587D01*
X27465D01*
X29286Y796766D01*
X31528Y794524D01*
X37832D01*
X52260Y780096D01*
X80833D01*
X83352Y777577D01*
G37*
G36*
G01X123137Y29903D02*
X123053Y30050D01*
X123098Y30384D01*
X124249Y31535D01*
Y56764D01*
X131998Y64513D01*
X138895D01*
X138959Y64496D01*
G03X139067Y64469I952J3577D01*
G03X139471Y64396I859J3601D01*
G01X139472D01*
X139500Y64393D01*
G03X141813Y64889I421J3678D01*
G01X161912D01*
X162035Y65012D01*
X163571D01*
X164799Y66240D01*
Y72963D01*
X160124Y77638D01*
Y83344D01*
X160263Y83687D01*
X160321Y83752D01*
G03X160414Y83865I-1420J1264D01*
G03X160593Y84150I-1514J1150D01*
G03X158901Y86918I-1692J867D01*
G01X158281D01*
G02X157921Y87018I83J998D01*
G01Y89279D01*
G02X158283Y89380I445J-897D01*
G01X159417D01*
G03Y93182I0J1901D01*
G01X155370D01*
G03X155097Y93163I-5J-1901D01*
G03X155040Y93154I268J-1882D01*
G03X154947Y93135I334J-1872D01*
G03X154942Y93134I370J-1863D01*
G01X154887Y93121D01*
X153299D01*
X150250Y90072D01*
X143296D01*
G02X142894Y90274I0J500D01*
G03X136668Y89841I-2975J-2203D01*
G03X136543Y89590I3249J-1774D01*
G01X136483Y89457D01*
X136236Y89296D01*
X123604D01*
X123356Y89457D01*
X123296Y89591D01*
G03X116544I-3376J-1520D01*
G01X116484Y89457D01*
X116236Y89296D01*
X115620D01*
G02X115120Y89774I0J501D01*
G01Y353796D01*
X118080Y356756D01*
X127045D01*
X132980Y362691D01*
Y421942D01*
X135138Y424100D01*
X136544D01*
G02X136946Y423898I0J-500D01*
G03X137346Y423441I2976J2201D01*
G03X137425Y423367I2570J2664D01*
G03X138339Y422754I2496J2734D01*
G03X139553Y422418I1580J3348D01*
G03X140465Y422440I367J3684D01*
G01X140583Y422458D01*
X140807Y422384D01*
X144933Y418258D01*
G02X144580Y417404I-353J-354D01*
G01X143571D01*
X143327Y417559D01*
X143265Y417690D01*
G03Y414514I-3345J-1588D01*
G01X143327Y414645D01*
X143571Y414800D01*
X147128D01*
X148182Y413746D01*
X154819D01*
Y413646D01*
X157823D01*
Y413744D01*
X159754D01*
Y413643D01*
X162758D01*
Y416870D01*
G03X163258Y418194I-1501J1323D01*
G01Y420869D01*
G03X159256I-2001J0D01*
G01Y418773D01*
G02X158756Y418273I-500J0D01*
G02X158269Y418658I0J500D01*
G03X157923Y419398I-1948J-460D01*
G01X157770Y419600D01*
X157763D01*
X157621Y419720D01*
G03X157267Y419962I-1300J-1522D01*
G03X156321Y420200I-947J-1764D01*
G01X148653D01*
X143638Y425215D01*
X143564Y425439D01*
X143582Y425557D01*
G03X141186Y429581I-3662J545D01*
G03X140998Y429644I-1270J-3477D01*
G03X136946Y428306I-1077J-3542D01*
G02X136544Y428104I-402J298D01*
G01X133480D01*
X128976Y423600D01*
Y364349D01*
X125387Y360760D01*
X118080D01*
X117893Y360946D01*
X108135Y370704D01*
X105521D01*
G02X105070Y371204I52J500D01*
G01Y373411D01*
X104970D01*
Y374978D01*
X105270Y375278D01*
X105899D01*
X106023Y375198D01*
G03X106343Y375042I814J1263D01*
G01X106452Y375004D01*
X106656Y374800D01*
X116269D01*
X116513Y374645D01*
X116575Y374514D01*
G03Y377690I3345J1588D01*
G01X116513Y377559D01*
X116269Y377404D01*
X108224D01*
X107882Y377542D01*
X107819Y377597D01*
G03X107648Y377725I-983J-1135D01*
G03X107334Y377878I-810J-1264D01*
G03X106413Y377902I-498J-1417D01*
G01X106344Y377882D01*
X105270D01*
X105070Y378082D01*
X104970D01*
Y379884D01*
X105070D01*
Y382888D01*
X103020D01*
G02X102520Y383388I0J500D01*
G01Y384233D01*
G02X103020Y384733I500J0D01*
G01X105070D01*
Y387737D01*
X104970D01*
Y389618D01*
X105270Y389918D01*
X105950D01*
X106053Y389868D01*
G03X106153Y389824I654J1352D01*
G03X106205Y389804I565J1391D01*
G03X106271Y389782I508J1413D01*
G03X107367Y389867I440J1437D01*
G01X107471Y389918D01*
X114105D01*
G02X114410Y389771I-52J-498D01*
G01X116316Y387865D01*
G02X116433Y387344I-354J-353D01*
G03X123336Y384675I3487J-1242D01*
G03X118712Y389602I-3415J1428D01*
G01X118674Y389588D01*
X118590Y389573D01*
G02X118151Y389712I-85J493D01*
G01X116199Y391664D01*
X115855Y392007D01*
X115342Y392520D01*
X107472D01*
X107369Y392571D01*
G03X106488Y392705I-656J-1352D01*
G03X106420Y392693I227J-1485D01*
G03X106262Y392653I289J-1474D01*
G03X106056Y392572I445J-1435D01*
G01X105953Y392522D01*
X105270D01*
X105070Y392722D01*
X104970D01*
Y394522D01*
X105070D01*
Y397526D01*
X101852D01*
X101718Y397626D01*
G03X101591Y397714I-1203J-1600D01*
G03X101396Y397823I-1073J-1690D01*
G03X101365Y397838I-887J-1794D01*
G03X101291Y397870I-831J-1821D01*
G03X101254Y397885I-770J-1847D01*
G01X101111Y397942D01*
X100938Y398196D01*
Y398350D01*
G02X101438Y398850I500J0D01*
G01X105346D01*
X105546Y399050D01*
X114647D01*
X118215Y402618D01*
X118499Y402680D01*
X118637Y402629D01*
G03X122691Y408557I1284J3472D01*
G03X122230Y408995I-2771J-2455D01*
G03X121059Y409624I-2309J-2894D01*
G03X116419Y404900I-1139J-3522D01*
G01X116466Y404764D01*
X116401Y404486D01*
X113569Y401654D01*
X105546D01*
X105346Y401854D01*
X104765D01*
G02X104058Y403561I0J1000D01*
G01X105835Y405338D01*
X105944Y405376D01*
G03X104032Y407288I-493J1419D01*
G01X103994Y407179D01*
X99492Y402677D01*
Y401854D01*
X99392D01*
Y398526D01*
G02X98892Y398026I-500J0D01*
G01X97643D01*
G03X96565Y394337I0J-2002D01*
G02X96679Y392737I-538J-842D01*
G03X97985Y389218I1306J-1517D01*
G01X100211D01*
G02X100711Y388718I0J-500D01*
G01Y388529D01*
X100462Y388246D01*
X100274Y388222D01*
G03X100218Y388214I255J-1985D01*
G01X100216D01*
G03X100120Y388196I321J-1975D01*
G01X100071Y388186D01*
X95870D01*
G02X95565Y388333I52J498D01*
G01X93032Y390866D01*
Y410758D01*
X89950Y413840D01*
Y425068D01*
X109840Y444958D01*
Y698268D01*
G02X110340Y698719I500J-52D01*
G01X147542D01*
X155525Y706702D01*
Y715728D01*
X155580D01*
Y733681D01*
G02X155726Y734034I500J0D01*
G01X169216Y747523D01*
Y750408D01*
X171238Y752430D01*
Y764547D01*
G02X171385Y764900I500J-1D01*
G01X172195Y765710D01*
Y771907D01*
X166996Y777106D01*
Y786321D01*
X164075Y789242D01*
X160032Y793286D01*
X150264D01*
X147776Y790798D01*
X143938D01*
G02X143133Y792295I63J999D01*
G03X136707I-3213J1839D01*
G02X135902Y790798I-868J-498D01*
G01X134758D01*
X133726Y789766D01*
X130940D01*
X124954Y795752D01*
X121979Y798728D01*
X116802D01*
X116594Y798936D01*
Y800048D01*
G02X118088Y800917I1000J0D01*
G03Y807351I1832J3217D01*
G02X116594Y808220I-494J869D01*
G01Y810048D01*
G02X118088Y810917I1000J0D01*
G03Y817351I1832J3217D01*
G02X116594Y818220I-494J869D01*
G01Y820048D01*
G02X118088Y820917I1000J0D01*
G03Y827351I1832J3217D01*
G02X116594Y828220I-494J869D01*
G01Y830048D01*
G02X118088Y830917I1000J0D01*
G03Y837351I1832J3217D01*
G02X116594Y838220I-494J869D01*
G01Y840048D01*
G02X118088Y840917I1000J0D01*
G03X121766Y840925I1832J3217D01*
G03X122050Y841106I-1846J3209D01*
G03X122937Y841988I-2129J3028D01*
G03X118226Y847426I-3017J2146D01*
G03X117493Y846930I1693J-3292D01*
G01X117428Y846873D01*
X117275Y846813D01*
G02X116594Y847279I-181J466D01*
G01Y848005D01*
X116687Y848135D01*
G03X114526Y851040I-1548J1105D01*
G02X113204Y851987I-322J947D01*
G01Y874726D01*
X113947Y875469D01*
Y1024914D01*
X144082Y1055049D01*
Y1084806D01*
X168198Y1108922D01*
Y1120722D01*
X161323Y1127597D01*
G02X160335Y1128751I0J1000D01*
G03X160349Y1129229I-1879J294D01*
G03X160149Y1129911I-1893J-185D01*
G03X158456Y1130946I-1693J-867D01*
G01X158270D01*
G02X157343Y1132024I71J998D01*
G03X157217Y1132893I-1996J154D01*
G02X158081Y1134250I934J359D01*
G01X159382D01*
G03Y1138052I0J1901D01*
G01X155283D01*
X153977Y1136746D01*
X153762D01*
Y1136520D01*
X153679Y1136394D01*
G03X153369Y1135498I1585J-1050D01*
G03X153363Y1135399I1894J-164D01*
G03X153366Y1135228I1901J-52D01*
G02X152438Y1134166I-999J-64D01*
G01X143296D01*
G02X142894Y1134368I0J500D01*
G03X136616Y1133834I-2974J-2203D01*
G03X136372Y1133222I3303J-1671D01*
G03X136324Y1133045I3547J-1057D01*
G03X136322Y1133037I3589J-901D01*
G03X136321Y1133032I3629J-728D01*
G01X136320Y1133028D01*
X136319Y1133023D01*
G02X135833Y1132640I-486J117D01*
G01X124007D01*
G02X123521Y1133024I0J500D01*
G03X118088Y1135382I-3601J-859D01*
G02X116594Y1136251I-494J869D01*
G01Y1138079D01*
G02X118088Y1138948I1000J0D01*
G03Y1145382I1832J3217D01*
G02X116594Y1146251I-494J869D01*
G01Y1148079D01*
G02X118088Y1148948I1000J0D01*
G03Y1155382I1832J3217D01*
G02X116594Y1156251I-494J869D01*
G01Y1158079D01*
G02X118088Y1158948I1000J0D01*
G03Y1165382I1832J3217D01*
G02X116594Y1166251I-494J869D01*
G01Y1168079D01*
G02X118088Y1168948I1000J0D01*
G03Y1175382I1832J3217D01*
G02X116594Y1176251I-494J869D01*
G01Y1178079D01*
G02X118088Y1178948I1000J0D01*
G03Y1185382I1832J3217D01*
G02X116594Y1186251I-494J869D01*
G01Y1188079D01*
G02X118088Y1188948I1000J0D01*
G03Y1195382I1832J3217D01*
G02X116594Y1196251I-494J869D01*
G01Y1198079D01*
G02X118088Y1198948I1000J0D01*
G03Y1205382I1832J3217D01*
G02X116594Y1206251I-494J869D01*
G01Y1208079D01*
G02X118088Y1208948I1000J0D01*
G03Y1215382I1832J3217D01*
G02X116594Y1216251I-494J869D01*
G01Y1218079D01*
G02X118088Y1218948I1000J0D01*
G03X121952Y1219070I1832J3217D01*
G03X123545Y1221413I-2032J3095D01*
G03X123621Y1222069I-3625J752D01*
G03X121065Y1225686I-3701J96D01*
G03X116346Y1223131I-1145J-3521D01*
G02X114681Y1222710I-958J286D01*
G01X110500Y1226891D01*
Y1339302D01*
X110565Y1339367D01*
Y1389154D01*
X110738Y1389327D01*
Y1394224D01*
X111999Y1395485D01*
X125305D01*
X134550Y1404730D01*
Y1432464D01*
X138650Y1436564D01*
X138904Y1436635D01*
X139031Y1436603D01*
G03X141930Y1437088I889J3594D01*
G01X150940D01*
X165858Y1452006D01*
Y1475607D01*
X162495Y1478970D01*
X159678D01*
X159625Y1478982D01*
G03X159217Y1479026I-407J-1858D01*
G01X158409D01*
G02X157909Y1479526I0J500D01*
G01Y1481142D01*
X158277Y1481510D01*
X160589D01*
X161499Y1482420D01*
Y1484556D01*
X160571Y1485484D01*
X138949D01*
X138702Y1485731D01*
G02Y1486439I353J354D01*
G01X138791Y1486528D01*
X139034Y1486600D01*
X139158Y1486574D01*
G03X136232Y1490523I762J3623D01*
G02X134529Y1489904I-996J88D01*
G01X123563Y1500870D01*
X123531Y1501011D01*
G03X120734Y1503808I-3611J-814D01*
G01X120593Y1503840D01*
X119627Y1504806D01*
G02X120246Y1506509I707J707D01*
G03X123622Y1510217I-326J3688D01*
G03X118182Y1513466I-3702J-20D01*
G03X117436Y1512942I1739J-3269D01*
G02X115765Y1513683I-671J741D01*
G01Y1516711D01*
G02X117436Y1517452I1000J0D01*
G03Y1522942I2484J2745D01*
G02X115765Y1523683I-671J741D01*
G01Y1526711D01*
G02X117436Y1527452I1000J0D01*
G03Y1532942I2484J2745D01*
G02X115765Y1533683I-671J741D01*
G01Y1536711D01*
G02X117436Y1537452I1000J0D01*
G03Y1542942I2484J2745D01*
G02X115765Y1543683I-671J741D01*
G01Y1546711D01*
G02X117436Y1547452I1000J0D01*
G03Y1552942I2484J2745D01*
G02X115765Y1553683I-671J741D01*
G01Y1556711D01*
G02X117436Y1557452I1000J0D01*
G03Y1562942I2484J2745D01*
G02X115765Y1563683I-671J741D01*
G01Y1566711D01*
G02X117436Y1567452I1000J0D01*
G03Y1572942I2484J2745D01*
G02X115765Y1573683I-671J741D01*
G01Y1576711D01*
G02X117436Y1577452I1000J0D01*
G03Y1582942I2484J2745D01*
G02X115765Y1583683I-671J741D01*
G01Y1586711D01*
G02X117436Y1587452I1000J0D01*
G03Y1592942I2484J2745D01*
G02X115765Y1593683I-671J741D01*
G01Y1596711D01*
G02X117436Y1597452I1000J0D01*
G03Y1602942I2484J2745D01*
G02X115765Y1603683I-671J741D01*
G01Y1736585D01*
X115750Y1736600D01*
Y1737012D01*
X125190Y1746452D01*
Y1798885D01*
X127219Y1800914D01*
X134576Y1808270D01*
G02X136253Y1807719I692J-722D01*
G03X136486Y1806845I3667J509D01*
G03X137034Y1805909I3434J1382D01*
G03X143207Y1806522I2887J2318D01*
G01X143269Y1806642D01*
X143716Y1806926D01*
X150348D01*
X156714Y1813292D01*
Y1813524D01*
G02X157214Y1814024I500J0D01*
G01X157361D01*
X157484Y1813945D01*
G03X157641Y1813854I1081J1684D01*
G03X158077Y1813689I922J1777D01*
G03X158295Y1813647I487J1942D01*
G03X158438Y1813633I266J1984D01*
G03X158466Y1813632I85J1999D01*
G03X158571Y1813630I91J1999D01*
G01X161005Y1813639D01*
X162974Y1813647D01*
X163005Y1813643D01*
G03X163478Y1813642I241J1988D01*
G03X164315Y1813936I-228J1989D01*
G03X164416Y1814004I-1067J1694D01*
G03X164869Y1814454I-1166J1627D01*
G03X165252Y1815631I-1617J1177D01*
G01Y1815650D01*
G03X164231Y1817395I-2002J0D01*
G03X164068Y1817477I-980J-1745D01*
G03X163242Y1817651I-816J-1827D01*
G01X161165Y1817643D01*
X160363Y1817640D01*
G02X159860Y1818140I-3J500D01*
G01Y1818545D01*
X159961Y1818646D01*
Y1821862D01*
X157810D01*
G02X157310Y1822362I0J500D01*
G01Y1822456D01*
X157258Y1822715D01*
X157326Y1822878D01*
G02X157788Y1823185I461J-193D01*
G01X159075D01*
G03X160722Y1824136I0J1902D01*
G03X160965Y1825298I-1647J951D01*
G03X160889Y1825658I-1890J-211D01*
G03X160842Y1825788I-1811J-581D01*
G03X159075Y1826988I-1767J-701D01*
G01X158566D01*
G02X157650Y1828049I83J998D01*
G03X157657Y1828179I-1994J173D01*
G01Y1828215D01*
G03X157647Y1828433I-2001J17D01*
G02X158647Y1829478I999J45D01*
G01X159822D01*
G03Y1833282I0J1902D01*
G01X155570D01*
G03X154285Y1832782I0J-1902D01*
G01X154068D01*
Y1832556D01*
X153985Y1832430D01*
G03X153943Y1832364I1583J-1054D01*
G03X153893Y1832277I1623J-991D01*
G03X153825Y1832136I1677J-896D01*
G03X153685Y1831633I1745J-757D01*
G03X153669Y1831321I1884J-253D01*
G03X153671Y1831281I1900J75D01*
G02X152672Y1830230I-998J-51D01*
G01X143296D01*
X142900Y1830429D01*
X142831Y1830517D01*
G03X136228Y1828501I-2911J-2288D01*
G03X136218Y1828191I3692J-274D01*
G03X136680Y1826437I3702J37D01*
G02X135784Y1824992I-896J-445D01*
G01X134977D01*
X124955Y1814969D01*
G02X124601Y1814822I-354J353D01*
G01X123929D01*
G02X123101Y1816334I31J1000D01*
G03X123194Y1816500I-3182J1892D01*
G03X123288Y1816691I-3273J1729D01*
G03X116950Y1820438I-3368J1537D01*
G03X116947Y1820434I2960J-2223D01*
G01X116878Y1820342D01*
X116472Y1820130D01*
X111710D01*
G02X110714Y1821215I0J1000D01*
G03X110719Y1821296I-1895J158D01*
G03X110720Y1821325I-1900J80D01*
G01Y1824470D01*
G03X106918I-1901J0D01*
G01Y1821317D01*
G03X106920Y1821274I1900J67D01*
G03X106921Y1821256I1898J96D01*
G03X106925Y1821207I1897J130D01*
G02X105840Y1820122I-996J-89D01*
G03X105571Y1820127I-170J-1894D01*
G03X105475Y1820120I90J-1899D01*
G03X105384Y1820108I203J-1890D01*
G03X104619Y1819813I286J-1880D01*
G01X104493Y1819730D01*
X104267D01*
Y1819524D01*
X104163Y1819389D01*
G03X104136Y1819353I1507J-1159D01*
G03X104131Y1819347I1455J-1218D01*
G03X103939Y1819018I1538J-1118D01*
G03X103883Y1818881I1731J-787D01*
G03X103768Y1818228I1786J-651D01*
G01Y1815227D01*
G03X104624Y1813638I1901J-1D01*
G03X104799Y1813536I1044J1590D01*
G03X104803Y1813534I851J1698D01*
G03X105832Y1813332I867J1693D01*
G02X106918Y1812418I88J-997D01*
G01Y1812069D01*
G03X106919Y1812033I1901J35D01*
G03X106922Y1811981I1900J84D01*
G03X106931Y1811889I1896J139D01*
G03X106934Y1811865I1888J224D01*
G03X106935Y1811857I1888J232D01*
G03X106936Y1811851I1873J309D01*
G03X106941Y1811821I1878J298D01*
G01Y1811819D01*
X106947Y1811780D01*
Y1811740D01*
G02X106469Y1811240I-500J0D01*
G01X99308D01*
X96520Y1808452D01*
X90982Y1802915D01*
Y1785399D01*
G02X90482Y1784899I-500J0D01*
G01X71100D01*
X68873Y1787126D01*
X66622Y1789376D01*
X66092D01*
G02X65745Y1789516I0J500D01*
G03X62398Y1788495I-1390J-1441D01*
G03X62354Y1788112I1958J-419D01*
G01X62350Y1787910D01*
X61943Y1787503D01*
X61846Y1787405D01*
X61336Y1786895D01*
Y1784486D01*
X61236D01*
Y1781484D01*
X64038D01*
Y1784486D01*
X63938D01*
Y1785574D01*
G02X64422Y1786074I500J0D01*
G03X64499Y1786078I-65J2001D01*
G03X64639Y1786093I-143J1997D01*
G03X64747Y1786112I-293J1980D01*
G03X65404Y1786370I-392J1963D01*
G01X65405Y1786371D01*
G02X66019Y1786298I261J-427D01*
G01X68728Y1783589D01*
Y1776667D01*
X68792Y1776603D01*
X74329D01*
X74495Y1776437D01*
Y1774226D01*
X73606Y1773337D01*
Y1757608D01*
X74296Y1756918D01*
Y1753825D01*
X73896Y1753425D01*
Y1752310D01*
G02X73756Y1751963I-500J0D01*
G03X74487Y1748702I1442J-1389D01*
G01X74588Y1748664D01*
X77184Y1746068D01*
X78390D01*
G02X78890Y1745568I0J-500D01*
G01Y1745026D01*
X84292D01*
Y1745612D01*
G02X84792Y1746068I500J-46D01*
G01X85870D01*
G02X86370Y1745568I0J-500D01*
G01Y1745026D01*
X91772D01*
Y1745612D01*
G02X92272Y1746068I500J-46D01*
G01X97794D01*
X109999Y1733863D01*
Y1497368D01*
X103135Y1490504D01*
Y1470053D01*
X88741Y1455659D01*
Y1428797D01*
X88754D01*
Y1398654D01*
X88735Y1398636D01*
Y1366456D01*
X83674Y1361395D01*
X48375D01*
X45714Y1364056D01*
Y1382826D01*
X34788Y1393752D01*
X19175D01*
X9690Y1403237D01*
Y1556406D01*
G02X10958Y1557369I1000J0D01*
G03X11227Y1557307I583J1915D01*
G03X11790Y1557298I313J1977D01*
G03X11827Y1557303I-250J1986D01*
G03X12564Y1557563I-285J1981D01*
G03X12741Y1557682I-1027J1718D01*
G01X12875Y1557782D01*
X16093D01*
Y1560786D01*
X15992D01*
Y1567532D01*
G02X16156Y1567903I500J1D01*
G03X14208Y1573300I-2083J2298D01*
G03X12686Y1572976I-136J-3099D01*
G03X13054Y1567271I1386J-2775D01*
G02X13390Y1566799I-164J-472D01*
G01Y1565146D01*
G02X12107Y1564250I-999J64D01*
G03X11929Y1564294I-569J-1919D01*
G03X11346Y1564322I-386J-1964D01*
G03X11140Y1564291I194J-1992D01*
G03X10958Y1564245I399J-1961D01*
G02X9690Y1565208I-268J963D01*
G01Y1611340D01*
G02X9999Y1611802I500J0D01*
G01X10139Y1611859D01*
X10436Y1611800D01*
X10946Y1611290D01*
G02X11076Y1610807I-353J-354D01*
G03X13090Y1607062I2996J-803D01*
G03X16312Y1612151I983J2942D01*
G03X13298Y1613008I-2239J-2147D01*
G01X13269Y1613001D01*
X13203Y1612992D01*
G02X12784Y1613134I-66J496D01*
G01X11848Y1614070D01*
Y1615955D01*
G02X13147Y1616846I999J-64D01*
G03X15933Y1617324I926J2961D01*
G03X17078Y1620579I-1860J2483D01*
G01X17077Y1620582D01*
X17070Y1620611D01*
X17061Y1620675D01*
G02X17203Y1621096I496J67D01*
G01X17854Y1621747D01*
Y1630551D01*
X18054Y1630751D01*
Y1633980D01*
G03X18554Y1635303I-1502J1324D01*
G01Y1638005D01*
G03X14550I-2002J0D01*
G01Y1635303D01*
G03X15050Y1633980I2002J1D01*
G01Y1630751D01*
X15250Y1630551D01*
Y1623905D01*
G02X14220Y1622906I-1000J0D01*
G03X13991Y1622908I-142J-3099D01*
G03X13147Y1622768I81J-3101D01*
G02X11848Y1623659I-300J955D01*
G01Y1630427D01*
G02X12348Y1630883I500J-46D01*
G01X12655D01*
Y1634112D01*
G03X12877Y1634417I-1500J1325D01*
G03X13047Y1634787I-1724J1016D01*
G03X13111Y1635018I-1893J649D01*
G03X13154Y1635435I-1958J413D01*
G01Y1638435D01*
G03X10952Y1640426I-2001J0D01*
G03X10810Y1640407I194J-1992D01*
G02X9690Y1641400I-120J993D01*
G01Y1863723D01*
X20945Y1874978D01*
X26408D01*
Y1882282D01*
X19104D01*
Y1876819D01*
X9868Y1867583D01*
G02X8190Y1868256I-679J736D01*
G01Y1944223D01*
X20945Y1956978D01*
X26408D01*
Y1964280D01*
X19104D01*
Y1958818D01*
X8368Y1948082D01*
G02X6690Y1948755I-679J736D01*
G01Y2017723D01*
X20945Y2031978D01*
X26408D01*
Y2039280D01*
X19104D01*
Y2033818D01*
X6707Y2021421D01*
G02X5000Y2022128I-707J707D01*
G01Y2064961D01*
X5905Y2065866D01*
X92520D01*
G03X98062Y2067380I-1J10905D01*
G03X98724Y2067804I-5546J9389D01*
G01X98725D01*
X98732Y2067810D01*
G03X100230Y2069061I-6213J8962D01*
G03X100715Y2069579I-7713J7708D01*
G03X100734Y2069600I-8075J7325D01*
G03X101039Y2069965I-8213J7173D01*
G03X101271Y2070266I-8519J6806D01*
G03X101911Y2071230I-8752J6505D01*
G03X103424Y2076772I-9392J5542D01*
G01Y2080709D01*
G02X104288Y2081614I907J-1D01*
G01X397638D01*
G02X400512Y2078740I0J-2874D01*
G01Y15903D01*
X394161Y9552D01*
X113112D01*
X111151Y11513D01*
Y25370D01*
X112404Y26623D01*
G02X112757Y26770I354J-353D01*
G01X116269D01*
X116513Y26615D01*
X116575Y26484D01*
G03X123437Y29228I3346J1585D01*
G03X123312Y29554I-3515J-1161D01*
G03X123137Y29903I-3392J-1483D01*
G37*
G36*
G01X65354Y795260D02*
G02I0J19700D01*
G37*
G36*
G01Y1145260D02*
G02I0J19700D01*
G37*
G36*
G01X86364Y1289755D02*
Y1260873D01*
X76681Y1251190D01*
X60105D01*
X59652Y1251643D01*
Y1254804D01*
X58812Y1255644D01*
X53839D01*
X53244Y1256239D01*
Y1260125D01*
Y1285444D01*
Y1290382D01*
X54504Y1291642D01*
X57356D01*
X57358Y1291640D01*
X60044D01*
X70206D01*
X84479D01*
X86364Y1289755D01*
G37*
G36*
G01X84330Y1771614D02*
X84317Y1771558D01*
G03Y1770648I1949J-455D01*
G01X84330Y1770592D01*
Y1761317D01*
X84356Y1761292D01*
Y1760988D01*
X84658D01*
X86075Y1759572D01*
Y1757060D01*
X85533Y1756518D01*
X76112D01*
X74607Y1758023D01*
Y1769498D01*
X77498Y1772390D01*
G03X78313Y1775129I-2122J2122D01*
G02X79292Y1776334I979J205D01*
G01X82997D01*
X83634Y1775697D01*
Y1773811D01*
X84330Y1773115D01*
Y1771614D01*
G37*
%LPC*%
G75*
G36*
G01X78620Y678708D02*
X72180D01*
G02X71094Y679029I1J2002D01*
G01X70970Y679108D01*
X68278D01*
Y682312D01*
X70970D01*
X71094Y682391D01*
G02X72111Y682710I1086J-1681D01*
G03Y683710I-18J500D01*
G02X71094Y684029I69J2000D01*
G01X70970Y684108D01*
X68278D01*
Y687312D01*
X70970D01*
X71094Y687391D01*
G02X72180Y687712I1087J-1681D01*
G01X79536D01*
G02X81044Y684394I0J-2002D01*
G03X81041Y683740I377J-329D01*
G02X80935Y681024I-1521J-1301D01*
G01X78620Y678708D01*
G37*
G36*
G01X11839Y499965D02*
X11939Y500098D01*
Y503317D01*
X12140Y503518D01*
Y509541D01*
G03X11977Y509910I-500J0D01*
G02X15080Y509263I2096J2287D01*
G01X14928Y509211D01*
X14742Y508951D01*
Y503518D01*
X14943Y503317D01*
Y500098D01*
X15043Y499965D01*
G02X15442Y498765I-1602J-1199D01*
G01Y495961D01*
G02X11440I-2001J0D01*
G01Y498765D01*
G02X11839Y499965I2001J1D01*
G37*
G36*
G01X92980Y678708D02*
X86187D01*
G02Y682712I0J2002D01*
G01X86551D01*
G03X87051Y683212I0J500D01*
G01Y683412D01*
X86775Y683701D01*
X86575Y683711D01*
G02X86673Y687712I98J1999D01*
G01X92980D01*
G02X94066Y687391I-1J-2002D01*
G01X94190Y687312D01*
X96882D01*
Y684108D01*
X94190D01*
X94066Y684029D01*
G02X93049Y683710I-1086J1681D01*
G03Y682710I18J-500D01*
G02X94066Y682391I-69J-2000D01*
G01X94190Y682312D01*
X96882D01*
Y679108D01*
X94190D01*
X94066Y679029D01*
G02X92980Y678708I-1087J1681D01*
G37*
G36*
G01X13141Y554962D02*
X13271Y554996D01*
G02X11077Y552802I802J-2996D01*
G01X11111Y552932D01*
X11042Y553190D01*
X8368Y555865D01*
Y565916D01*
X9612Y567161D01*
Y571458D01*
X9412Y571659D01*
Y574878D01*
X9312Y575011D01*
G02X8912Y576211I1602J1201D01*
G01Y578848D01*
G02X12916I2002J0D01*
G01Y576211D01*
G02X12516Y575011I-2002J1D01*
G01X12416Y574878D01*
Y571659D01*
X12216Y571458D01*
Y566083D01*
X10970Y564838D01*
Y564293D01*
G03X11470Y563793I500J0D01*
G01X11573D01*
X11761Y563873D01*
X11832Y563948D01*
G02X13778Y564891I2241J-2145D01*
G03X14682Y565886I-96J995D01*
G01Y571524D01*
X14482Y571725D01*
Y574944D01*
X14382Y575077D01*
G02X13982Y576277I1602J1201D01*
G01Y578849D01*
G02X17986I2002J0D01*
G01Y576277D01*
G02X17586Y575077I-2002J1D01*
G01X17486Y574944D01*
Y571725D01*
X17286Y571524D01*
Y563175D01*
X17104Y562993D01*
X17035Y562735D01*
X17069Y562605D01*
G02X12483Y559139I-2996J-802D01*
G03X10970Y558281I-513J-858D01*
G01Y556943D01*
X12883Y555031D01*
X13141Y554962D01*
G37*
G36*
G01X95516Y1874053D02*
G02X36114Y1853236I-30162J-9093D01*
G03X34290Y1853251I-915J-403D01*
G02X32788Y1858515I-3818J1757D01*
G03X34324Y1859522I551J835D01*
G02X95516Y1874053I31029J5443D01*
G37*
G36*
G01X170004Y727205D02*
G02X156767Y727182I-6619J0D01*
G02X169983Y727726I6618J30D01*
G02X169986Y727689I-6594J-553D01*
G02X170004Y727205I-6600J-488D01*
G37*
G36*
G01Y552205D02*
G02X156767Y552182I-6619J0D01*
G02X169983Y552726I6618J30D01*
G02X169986Y552689I-6594J-553D01*
G02X170004Y552205I-6600J-488D01*
G37*
G36*
G01X157357Y399788D02*
X157249Y399750D01*
X152299Y394800D01*
X143571D01*
X143327Y394645D01*
X143265Y394515D01*
G02Y397689I-3345J1587D01*
G01X143327Y397559D01*
X143571Y397404D01*
X151221D01*
X155408Y401591D01*
X155412Y401601D01*
Y402408D01*
G03X155265Y402761I-500J-1D01*
G01X153886Y404140D01*
Y407575D01*
G02X153938Y407958I1454J-2D01*
G01Y409077D01*
X157157D01*
X157290Y409177D01*
G02X158489Y409576I1199J-1602D01*
G01X161377D01*
G02Y405574I0J-2001D01*
G01X158490D01*
G02X157454Y405863I0J2001D01*
G03X156841Y405788I-259J-428D01*
G01X156794Y405741D01*
Y405344D01*
X158318Y403819D01*
Y401587D01*
G02X157357Y399788I-1453J-380D01*
G37*
G36*
G01X312560Y2004407D02*
Y2009087D01*
G02X316564I2002J0D01*
G01Y2004407D01*
G02X316483Y2003847I-2001J4D01*
G01X316464Y2003778D01*
Y2002306D01*
X312660D01*
Y2003778D01*
X312641Y2003847D01*
G02X312560Y2004407I1920J564D01*
G37*
G36*
G01X169982Y1952727D02*
G02X170003Y1952205I-6597J-527D01*
G02X156766I-6618J0D01*
G02X169982Y1952727I6618J0D01*
G37*
G36*
G01X177767Y1917015D02*
G03X176567I-600J-800D01*
G02Y1919419I-900J1202D01*
G03X177767I600J800D01*
G02Y1917015I900J-1202D01*
G37*
G36*
G01X170271D02*
G03X169071I-600J-800D01*
G02Y1919419I-900J1202D01*
G03X170271I600J800D01*
G02Y1917015I900J-1202D01*
G37*
G36*
G01X161448D02*
G03X160248I-600J-800D01*
G02Y1919419I-900J1202D01*
G03X161448I600J800D01*
G02Y1917015I900J-1202D01*
G37*
G36*
G01X154020D02*
G03X152820I-600J-800D01*
G02Y1919419I-900J1202D01*
G03X154020I600J800D01*
G02Y1917015I900J-1202D01*
G37*
G36*
G01X177767Y1909496D02*
G03X176567I-600J-800D01*
G02Y1911900I-900J1202D01*
G03X177767I600J800D01*
G02Y1909496I900J-1202D01*
G37*
G36*
G01X170271D02*
G03X169071I-600J-800D01*
G02Y1911900I-900J1202D01*
G03X170271I600J800D01*
G02Y1909496I900J-1202D01*
G37*
G36*
G01X161448D02*
G03X160248I-600J-800D01*
G02Y1911900I-900J1202D01*
G03X161448I600J800D01*
G02Y1909496I900J-1202D01*
G37*
G36*
G01X154020D02*
G03X152820I-600J-800D01*
G02Y1911900I-900J1202D01*
G03X154020I600J800D01*
G02Y1909496I900J-1202D01*
G37*
G36*
G01X177767Y1901460D02*
G03X176567I-600J-800D01*
G02Y1903864I-900J1202D01*
G03X177767I600J800D01*
G02Y1901460I900J-1202D01*
G37*
G36*
G01X170271D02*
G03X169071I-600J-800D01*
G02Y1903864I-900J1202D01*
G03X170271I600J800D01*
G02Y1901460I900J-1202D01*
G37*
G36*
G01X161448D02*
G03X160248I-600J-800D01*
G02Y1903864I-900J1202D01*
G03X161448I600J800D01*
G02Y1901460I900J-1202D01*
G37*
G36*
G01X154020D02*
G03X152820I-600J-800D01*
G02Y1903864I-900J1202D01*
G03X154020I600J800D01*
G02Y1901460I900J-1202D01*
G37*
G36*
G01X177767Y1894017D02*
G03X176567I-600J-800D01*
G02Y1896421I-900J1202D01*
G03X177767I600J800D01*
G02Y1894017I900J-1202D01*
G37*
G36*
G01X170271D02*
G03X169071I-600J-800D01*
G02Y1896421I-900J1202D01*
G03X170271I600J800D01*
G02Y1894017I900J-1202D01*
G37*
G36*
G01X161448D02*
G03X160248I-600J-800D01*
G02Y1896421I-900J1202D01*
G03X161448I600J800D01*
G02Y1894017I900J-1202D01*
G37*
G36*
G01X154020D02*
G03X152820I-600J-800D01*
G02Y1896421I-900J1202D01*
G03X154020I600J800D01*
G02Y1894017I900J-1202D01*
G37*
G36*
G01X177938Y1886099D02*
G03X176738I-600J-800D01*
G02Y1888503I-900J1202D01*
G03X177938I600J800D01*
G02Y1886099I900J-1202D01*
G37*
G36*
G01X170442D02*
G03X169242I-600J-800D01*
G02Y1888503I-900J1202D01*
G03X170442I600J800D01*
G02Y1886099I900J-1202D01*
G37*
G36*
G01X161619D02*
G03X160419I-600J-800D01*
G02Y1888503I-900J1202D01*
G03X161619I600J800D01*
G02Y1886099I900J-1202D01*
G37*
G36*
G01X154191D02*
G03X152991I-600J-800D01*
G02Y1888503I-900J1202D01*
G03X154191I600J800D01*
G02Y1886099I900J-1202D01*
G37*
G36*
G01X177938Y1879504D02*
G03X176738I-600J-800D01*
G02Y1881908I-900J1202D01*
G03X177938I600J800D01*
G02Y1879504I900J-1202D01*
G37*
G36*
G01X170442D02*
G03X169242I-600J-800D01*
G02Y1881908I-900J1202D01*
G03X170442I600J800D01*
G02Y1879504I900J-1202D01*
G37*
G36*
G01X161619D02*
G03X160419I-600J-800D01*
G02Y1881908I-900J1202D01*
G03X161619I600J800D01*
G02Y1879504I900J-1202D01*
G37*
G36*
G01X154191D02*
G03X152991I-600J-800D01*
G02Y1881908I-900J1202D01*
G03X154191I600J800D01*
G02Y1879504I900J-1202D01*
G37*
G36*
G01X177938Y1872020D02*
G03X176738I-600J-800D01*
G02Y1874424I-900J1202D01*
G03X177938I600J800D01*
G02Y1872020I900J-1202D01*
G37*
G36*
G01X170442D02*
G03X169242I-600J-800D01*
G02Y1874424I-900J1202D01*
G03X170442I600J800D01*
G02Y1872020I900J-1202D01*
G37*
G36*
G01X161619D02*
G03X160419I-600J-800D01*
G02Y1874424I-900J1202D01*
G03X161619I600J800D01*
G02Y1872020I900J-1202D01*
G37*
G36*
G01X154191D02*
G03X152991I-600J-800D01*
G02Y1874424I-900J1202D01*
G03X154191I600J800D01*
G02Y1872020I900J-1202D01*
G37*
G36*
G01X161619Y1864801D02*
G03X160419I-600J-800D01*
G02Y1867205I-900J1202D01*
G03X161619I600J800D01*
G02Y1864801I900J-1202D01*
G37*
G36*
G01X154191D02*
G03X152991I-600J-800D01*
G02Y1867205I-900J1202D01*
G03X154191I600J800D01*
G02Y1864801I900J-1202D01*
G37*
G36*
G01X286964Y1863280D02*
Y1863064D01*
X286738D01*
X286613Y1862980D01*
G02X285562Y1862664I-1050J1585D01*
G01X279976D01*
G02Y1866466I0J1901D01*
G01X285562D01*
G02X286613Y1866150I1J-1901D01*
G01X286738Y1866066D01*
X286964D01*
Y1865850D01*
G02Y1863280I-1402J-1285D01*
G37*
G36*
G01X293606Y1856666D02*
X288794D01*
G02X287594Y1857066I1J2002D01*
G01X287461Y1857166D01*
X286820D01*
X286694Y1857083D01*
G02X285644Y1856766I-1051J1585D01*
G01X280240D01*
G02Y1860570I0J1902D01*
G01X285644D01*
G02X286694Y1860253I-1J-1902D01*
G01X286820Y1860170D01*
X287461D01*
X287594Y1860270D01*
G02X288794Y1860670I1201J-1602D01*
G01X293606D01*
G02Y1856666I0J-2002D01*
G37*
G36*
G01X279064Y1829871D02*
Y1834569D01*
G02X283068I2002J0D01*
G01Y1829871D01*
G02X282987Y1829311I-2001J4D01*
G01X282968Y1829242D01*
Y1827770D01*
X279164D01*
Y1829242D01*
X279145Y1829311D01*
G02X279064Y1829871I1920J564D01*
G37*
G36*
G01X143265Y1789815D02*
X143327Y1789685D01*
X143571Y1789530D01*
X145866D01*
X155150Y1798814D01*
Y1800063D01*
X155100Y1800166D01*
G02Y1801476I1352J655D01*
G01X155150Y1801579D01*
Y1804639D01*
X154388Y1805401D01*
Y1806238D01*
X154288D01*
Y1809242D01*
X157507D01*
X157640Y1809342D01*
G02X158840Y1809742I1201J-1602D01*
G01X162140D01*
G02Y1805738I0J-2002D01*
G01X158840D01*
G02X158782Y1805739I6J2002D01*
G03X157754Y1804740I-28J-999D01*
G01Y1801579D01*
X157804Y1801476D01*
G02Y1800166I-1352J-655D01*
G01X157754Y1800063D01*
Y1797736D01*
X146944Y1786926D01*
X143571D01*
X143327Y1786771D01*
X143265Y1786641D01*
G02Y1789815I-3345J1587D01*
G37*
G36*
G01X61130Y1777071D02*
X61010Y1776930D01*
Y1776870D01*
X60943D01*
X60810Y1776770D01*
G02X59610Y1776370I-1200J1601D01*
G01X56425D01*
G02Y1780372I0J2001D01*
G01X59609D01*
G02X60810Y1779972I1J-2001D01*
G01X60943Y1779872D01*
X61010D01*
Y1779812D01*
X61130Y1779671D01*
G02Y1777071I-1521J-1300D01*
G37*
G36*
G01X169982Y1777727D02*
G02X170003Y1777205I-6597J-527D01*
G02X156766I-6618J0D01*
G02X169982Y1777727I6618J0D01*
G37*
G36*
G01X55544Y1772836D02*
X57088D01*
G03X57588Y1773336I0J500D01*
G01Y1774036D01*
X62990D01*
Y1767634D01*
X57588D01*
Y1768334D01*
G03X57088Y1768834I-500J0D01*
G01X55544D01*
G02Y1772836I0J2001D01*
G37*
G36*
G01X55080Y1764984D02*
X57088D01*
G03X57588Y1765484I0J500D01*
G01Y1766184D01*
X62990D01*
Y1759780D01*
X57588D01*
Y1760480D01*
G03X57088Y1760980I-500J0D01*
G01X55080D01*
G02Y1764984I0J2002D01*
G37*
G36*
G01X54948Y1757172D02*
X57088D01*
G03X57588Y1757672I0J500D01*
G01Y1758372D01*
X62990D01*
Y1751970D01*
X57588D01*
Y1752670D01*
G03X57088Y1753170I-500J0D01*
G01X54948D01*
G02Y1757172I0J2001D01*
G37*
G36*
G01X244807Y1714179D02*
G03X243607I-600J-800D01*
G02Y1716583I-900J1202D01*
G03X244807I600J800D01*
G02Y1714179I900J-1202D01*
G37*
G36*
G01X237311D02*
G03X236111I-600J-800D01*
G02Y1716583I-900J1202D01*
G03X237311I600J800D01*
G02Y1714179I900J-1202D01*
G37*
G36*
G01X228488D02*
G03X227288I-600J-800D01*
G02Y1716583I-900J1202D01*
G03X228488I600J800D01*
G02Y1714179I900J-1202D01*
G37*
G36*
G01X221060D02*
G03X219860I-600J-800D01*
G02Y1716583I-900J1202D01*
G03X221060I600J800D01*
G02Y1714179I900J-1202D01*
G37*
G36*
G01X244807Y1706660D02*
G03X243607I-600J-800D01*
G02Y1709064I-900J1202D01*
G03X244807I600J800D01*
G02Y1706660I900J-1202D01*
G37*
G36*
G01X237311D02*
G03X236111I-600J-800D01*
G02Y1709064I-900J1202D01*
G03X237311I600J800D01*
G02Y1706660I900J-1202D01*
G37*
G36*
G01X228488D02*
G03X227288I-600J-800D01*
G02Y1709064I-900J1202D01*
G03X228488I600J800D01*
G02Y1706660I900J-1202D01*
G37*
G36*
G01X221060D02*
G03X219860I-600J-800D01*
G02Y1709064I-900J1202D01*
G03X221060I600J800D01*
G02Y1706660I900J-1202D01*
G37*
G36*
G01X244807Y1698624D02*
G03X243607I-600J-800D01*
G02Y1701028I-900J1202D01*
G03X244807I600J800D01*
G02Y1698624I900J-1202D01*
G37*
G36*
G01X237311D02*
G03X236111I-600J-800D01*
G02Y1701028I-900J1202D01*
G03X237311I600J800D01*
G02Y1698624I900J-1202D01*
G37*
G36*
G01X228488D02*
G03X227288I-600J-800D01*
G02Y1701028I-900J1202D01*
G03X228488I600J800D01*
G02Y1698624I900J-1202D01*
G37*
G36*
G01X221060D02*
G03X219860I-600J-800D01*
G02Y1701028I-900J1202D01*
G03X221060I600J800D01*
G02Y1698624I900J-1202D01*
G37*
G36*
G01X244807Y1691181D02*
G03X243607I-600J-800D01*
G02Y1693585I-900J1202D01*
G03X244807I600J800D01*
G02Y1691181I900J-1202D01*
G37*
G36*
G01X237311D02*
G03X236111I-600J-800D01*
G02Y1693585I-900J1202D01*
G03X237311I600J800D01*
G02Y1691181I900J-1202D01*
G37*
G36*
G01X228488D02*
G03X227288I-600J-800D01*
G02Y1693585I-900J1202D01*
G03X228488I600J800D01*
G02Y1691181I900J-1202D01*
G37*
G36*
G01X221060D02*
G03X219860I-600J-800D01*
G02Y1693585I-900J1202D01*
G03X221060I600J800D01*
G02Y1691181I900J-1202D01*
G37*
G36*
G01X244978Y1683263D02*
G03X243778I-600J-800D01*
G02Y1685667I-900J1202D01*
G03X244978I600J800D01*
G02Y1683263I900J-1202D01*
G37*
G36*
G01X237482D02*
G03X236282I-600J-800D01*
G02Y1685667I-900J1202D01*
G03X237482I600J800D01*
G02Y1683263I900J-1202D01*
G37*
G36*
G01X228659D02*
G03X227459I-600J-800D01*
G02Y1685667I-900J1202D01*
G03X228659I600J800D01*
G02Y1683263I900J-1202D01*
G37*
G36*
G01X221231D02*
G03X220031I-600J-800D01*
G02Y1685667I-900J1202D01*
G03X221231I600J800D01*
G02Y1683263I900J-1202D01*
G37*
G36*
G01X244978Y1676668D02*
G03X243778I-600J-800D01*
G02Y1679072I-900J1202D01*
G03X244978I600J800D01*
G02Y1676668I900J-1202D01*
G37*
G36*
G01X237482D02*
G03X236282I-600J-800D01*
G02Y1679072I-900J1202D01*
G03X237482I600J800D01*
G02Y1676668I900J-1202D01*
G37*
G36*
G01X228659D02*
G03X227459I-600J-800D01*
G02Y1679072I-900J1202D01*
G03X228659I600J800D01*
G02Y1676668I900J-1202D01*
G37*
G36*
G01X221231D02*
G03X220031I-600J-800D01*
G02Y1679072I-900J1202D01*
G03X221231I600J800D01*
G02Y1676668I900J-1202D01*
G37*
G36*
G01X244978Y1669184D02*
G03X243778I-600J-800D01*
G02Y1671588I-900J1202D01*
G03X244978I600J800D01*
G02Y1669184I900J-1202D01*
G37*
G36*
G01X237482D02*
G03X236282I-600J-800D01*
G02Y1671588I-900J1202D01*
G03X237482I600J800D01*
G02Y1669184I900J-1202D01*
G37*
G36*
G01X228659D02*
G03X227459I-600J-800D01*
G02Y1671588I-900J1202D01*
G03X228659I600J800D01*
G02Y1669184I900J-1202D01*
G37*
G36*
G01X221231D02*
G03X220031I-600J-800D01*
G02Y1671588I-900J1202D01*
G03X221231I600J800D01*
G02Y1669184I900J-1202D01*
G37*
G36*
G01X228659Y1661965D02*
G03X227459I-600J-800D01*
G02Y1664369I-900J1202D01*
G03X228659I600J800D01*
G02Y1661965I900J-1202D01*
G37*
G36*
G01X221231D02*
G03X220031I-600J-800D01*
G02Y1664369I-900J1202D01*
G03X221231I600J800D01*
G02Y1661965I900J-1202D01*
G37*
G36*
G01X282084Y1655643D02*
Y1659883D01*
G02X286088I2002J0D01*
G01Y1655643D01*
G02X286007Y1655083I-2001J4D01*
G01X285988Y1655014D01*
Y1653542D01*
X282184D01*
Y1655014D01*
X282165Y1655083D01*
G02X282084Y1655643I1920J564D01*
G37*
G36*
G01X169982Y1602727D02*
G02X170003Y1602205I-6597J-527D01*
G02X156766I-6618J0D01*
G02X169982Y1602727I6618J0D01*
G37*
G36*
G01X179785Y1550233D02*
G03X178585I-600J-800D01*
G02Y1552637I-900J1202D01*
G03X179785I600J800D01*
G02Y1550233I900J-1202D01*
G37*
G36*
G01X172289D02*
G03X171089I-600J-800D01*
G02Y1552637I-900J1202D01*
G03X172289I600J800D01*
G02Y1550233I900J-1202D01*
G37*
G36*
G01X163466D02*
G03X162266I-600J-800D01*
G02Y1552637I-900J1202D01*
G03X163466I600J800D01*
G02Y1550233I900J-1202D01*
G37*
G36*
G01X156038D02*
G03X154838I-600J-800D01*
G02Y1552637I-900J1202D01*
G03X156038I600J800D01*
G02Y1550233I900J-1202D01*
G37*
G36*
G01X179785Y1542714D02*
G03X178585I-600J-800D01*
G02Y1545118I-900J1202D01*
G03X179785I600J800D01*
G02Y1542714I900J-1202D01*
G37*
G36*
G01X172289D02*
G03X171089I-600J-800D01*
G02Y1545118I-900J1202D01*
G03X172289I600J800D01*
G02Y1542714I900J-1202D01*
G37*
G36*
G01X163466D02*
G03X162266I-600J-800D01*
G02Y1545118I-900J1202D01*
G03X163466I600J800D01*
G02Y1542714I900J-1202D01*
G37*
G36*
G01X156038D02*
G03X154838I-600J-800D01*
G02Y1545118I-900J1202D01*
G03X156038I600J800D01*
G02Y1542714I900J-1202D01*
G37*
G36*
G01X179785Y1534678D02*
G03X178585I-600J-800D01*
G02Y1537082I-900J1202D01*
G03X179785I600J800D01*
G02Y1534678I900J-1202D01*
G37*
G36*
G01X172289D02*
G03X171089I-600J-800D01*
G02Y1537082I-900J1202D01*
G03X172289I600J800D01*
G02Y1534678I900J-1202D01*
G37*
G36*
G01X163466D02*
G03X162266I-600J-800D01*
G02Y1537082I-900J1202D01*
G03X163466I600J800D01*
G02Y1534678I900J-1202D01*
G37*
G36*
G01X156038D02*
G03X154838I-600J-800D01*
G02Y1537082I-900J1202D01*
G03X156038I600J800D01*
G02Y1534678I900J-1202D01*
G37*
G36*
G01X179785Y1527235D02*
G03X178585I-600J-800D01*
G02Y1529639I-900J1202D01*
G03X179785I600J800D01*
G02Y1527235I900J-1202D01*
G37*
G36*
G01X172289D02*
G03X171089I-600J-800D01*
G02Y1529639I-900J1202D01*
G03X172289I600J800D01*
G02Y1527235I900J-1202D01*
G37*
G36*
G01X163466D02*
G03X162266I-600J-800D01*
G02Y1529639I-900J1202D01*
G03X163466I600J800D01*
G02Y1527235I900J-1202D01*
G37*
G36*
G01X156038D02*
G03X154838I-600J-800D01*
G02Y1529639I-900J1202D01*
G03X156038I600J800D01*
G02Y1527235I900J-1202D01*
G37*
G36*
G01X307158Y1523116D02*
Y1522900D01*
X306932D01*
X306807Y1522816D01*
G02X305756Y1522500I-1050J1585D01*
G01X302267D01*
G02Y1526302I0J1901D01*
G01X305756D01*
G02X306807Y1525986I1J-1901D01*
G01X306932Y1525902D01*
X307158D01*
Y1525686D01*
G02Y1523116I-1402J-1285D01*
G37*
G36*
G01X179956Y1519317D02*
G03X178756I-600J-800D01*
G02Y1521721I-900J1202D01*
G03X179956I600J800D01*
G02Y1519317I900J-1202D01*
G37*
G36*
G01X172460D02*
G03X171260I-600J-800D01*
G02Y1521721I-900J1202D01*
G03X172460I600J800D01*
G02Y1519317I900J-1202D01*
G37*
G36*
G01X163637D02*
G03X162437I-600J-800D01*
G02Y1521721I-900J1202D01*
G03X163637I600J800D01*
G02Y1519317I900J-1202D01*
G37*
G36*
G01X156209D02*
G03X155009I-600J-800D01*
G02Y1521721I-900J1202D01*
G03X156209I600J800D01*
G02Y1519317I900J-1202D01*
G37*
G36*
G01X179956Y1512722D02*
G03X178756I-600J-800D01*
G02Y1515126I-900J1202D01*
G03X179956I600J800D01*
G02Y1512722I900J-1202D01*
G37*
G36*
G01X172460D02*
G03X171260I-600J-800D01*
G02Y1515126I-900J1202D01*
G03X172460I600J800D01*
G02Y1512722I900J-1202D01*
G37*
G36*
G01X163637D02*
G03X162437I-600J-800D01*
G02Y1515126I-900J1202D01*
G03X163637I600J800D01*
G02Y1512722I900J-1202D01*
G37*
G36*
G01X156209D02*
G03X155009I-600J-800D01*
G02Y1515126I-900J1202D01*
G03X156209I600J800D01*
G02Y1512722I900J-1202D01*
G37*
G36*
G01X308636Y1515884D02*
X313894D01*
G02Y1511882I0J-2001D01*
G01X308636D01*
G02X307436Y1512281I-1J2001D01*
G01X307303Y1512381D01*
X306662D01*
X306536Y1512298D01*
G02X305486Y1511982I-1050J1585D01*
G01X301734D01*
G02Y1515784I0J1901D01*
G01X305486D01*
G02X306536Y1515468I0J-1901D01*
G01X306662Y1515385D01*
X307303D01*
X307436Y1515485D01*
G02X308635Y1515884I1199J-1602D01*
G01X308636D01*
G37*
G36*
G01X179956Y1505238D02*
G03X178756I-600J-800D01*
G02Y1507642I-900J1202D01*
G03X179956I600J800D01*
G02Y1505238I900J-1202D01*
G37*
G36*
G01X172460D02*
G03X171260I-600J-800D01*
G02Y1507642I-900J1202D01*
G03X172460I600J800D01*
G02Y1505238I900J-1202D01*
G37*
G36*
G01X163637D02*
G03X162437I-600J-800D01*
G02Y1507642I-900J1202D01*
G03X163637I600J800D01*
G02Y1505238I900J-1202D01*
G37*
G36*
G01X156209D02*
G03X155009I-600J-800D01*
G02Y1507642I-900J1202D01*
G03X156209I600J800D01*
G02Y1505238I900J-1202D01*
G37*
G36*
G01X163637Y1498019D02*
G03X162437I-600J-800D01*
G02Y1500423I-900J1202D01*
G03X163637I600J800D01*
G02Y1498019I900J-1202D01*
G37*
G36*
G01X156209D02*
G03X155009I-600J-800D01*
G02Y1500423I-900J1202D01*
G03X156209I600J800D01*
G02Y1498019I900J-1202D01*
G37*
G36*
G01X268232Y1478962D02*
Y1482760D01*
G02X272236I2002J0D01*
G01Y1478962D01*
G02X272155Y1478402I-2001J4D01*
G01X272136Y1478333D01*
Y1476860D01*
X268332D01*
Y1478333D01*
X268313Y1478402D01*
G02X268232Y1478962I1920J564D01*
G37*
G36*
G01X169982Y1427727D02*
G02X170003Y1427205I-6597J-527D01*
G02X156766I-6618J0D01*
G02X169982Y1427727I6618J0D01*
G37*
G36*
G01X365269Y1375008D02*
G03X364069I-600J-800D01*
G02Y1377412I-900J1202D01*
G03X365269I600J800D01*
G02Y1375008I900J-1202D01*
G37*
G36*
G01X353491D02*
G03X352291I-600J-800D01*
G02Y1377412I-900J1202D01*
G03X353491I600J800D01*
G02Y1375008I900J-1202D01*
G37*
G36*
G01X365269Y1366569D02*
G03X364069I-600J-800D01*
G02Y1368973I-900J1202D01*
G03X365269I600J800D01*
G02Y1366569I900J-1202D01*
G37*
G36*
G01X353491D02*
G03X352291I-600J-800D01*
G02Y1368973I-900J1202D01*
G03X353491I600J800D01*
G02Y1366569I900J-1202D01*
G37*
G36*
G01X365269Y1358841D02*
G03X364069I-600J-800D01*
G02Y1361245I-900J1202D01*
G03X365269I600J800D01*
G02Y1358841I900J-1202D01*
G37*
G36*
G01X353491D02*
G03X352291I-600J-800D01*
G02Y1361245I-900J1202D01*
G03X353491I600J800D01*
G02Y1358841I900J-1202D01*
G37*
G36*
G01X365269Y1349504D02*
G03X364069I-600J-800D01*
G02Y1351908I-900J1202D01*
G03X365269I600J800D01*
G02Y1349504I900J-1202D01*
G37*
G36*
G01X353491D02*
G03X352291I-600J-800D01*
G02Y1351908I-900J1202D01*
G03X353491I600J800D01*
G02Y1349504I900J-1202D01*
G37*
G36*
G01X365269Y1338999D02*
G03X364069I-600J-800D01*
G02Y1341403I-900J1202D01*
G03X365269I600J800D01*
G02Y1338999I900J-1202D01*
G37*
G36*
G01X353491D02*
G03X352291I-600J-800D01*
G02Y1341403I-900J1202D01*
G03X353491I600J800D01*
G02Y1338999I900J-1202D01*
G37*
G36*
G01X365269Y1328484D02*
G03X364069I-600J-800D01*
G02Y1330888I-900J1202D01*
G03X365269I600J800D01*
G02Y1328484I900J-1202D01*
G37*
G36*
G01X353491D02*
G03X352291I-600J-800D01*
G02Y1330888I-900J1202D01*
G03X353491I600J800D01*
G02Y1328484I900J-1202D01*
G37*
G36*
G01X281806Y1305422D02*
Y1308959D01*
G02X285810I2002J0D01*
G01Y1305422D01*
G02X285729Y1304862I-2001J4D01*
G01X285710Y1304793D01*
Y1303320D01*
X281906D01*
Y1304793D01*
X281887Y1304862D01*
G02X281806Y1305422I1920J564D01*
G37*
G36*
G01X169982Y1252727D02*
G02X170003Y1252205I-6597J-527D01*
G02X156766I-6618J0D01*
G02X169982Y1252727I6618J0D01*
G37*
G36*
G01X254078Y1214094D02*
G03X252878I-600J-800D01*
G02Y1216498I-900J1202D01*
G03X254078I600J800D01*
G02Y1214094I900J-1202D01*
G37*
G36*
G01X246582D02*
G03X245382I-600J-800D01*
G02Y1216498I-900J1202D01*
G03X246582I600J800D01*
G02Y1214094I900J-1202D01*
G37*
G36*
G01X237759D02*
G03X236559I-600J-800D01*
G02Y1216498I-900J1202D01*
G03X237759I600J800D01*
G02Y1214094I900J-1202D01*
G37*
G36*
G01X230331D02*
G03X229131I-600J-800D01*
G02Y1216498I-900J1202D01*
G03X230331I600J800D01*
G02Y1214094I900J-1202D01*
G37*
G36*
G01X254078Y1206575D02*
G03X252878I-600J-800D01*
G02Y1208979I-900J1202D01*
G03X254078I600J800D01*
G02Y1206575I900J-1202D01*
G37*
G36*
G01X246582D02*
G03X245382I-600J-800D01*
G02Y1208979I-900J1202D01*
G03X246582I600J800D01*
G02Y1206575I900J-1202D01*
G37*
G36*
G01X237759D02*
G03X236559I-600J-800D01*
G02Y1208979I-900J1202D01*
G03X237759I600J800D01*
G02Y1206575I900J-1202D01*
G37*
G36*
G01X230331D02*
G03X229131I-600J-800D01*
G02Y1208979I-900J1202D01*
G03X230331I600J800D01*
G02Y1206575I900J-1202D01*
G37*
G36*
G01X254078Y1198539D02*
G03X252878I-600J-800D01*
G02Y1200943I-900J1202D01*
G03X254078I600J800D01*
G02Y1198539I900J-1202D01*
G37*
G36*
G01X246582D02*
G03X245382I-600J-800D01*
G02Y1200943I-900J1202D01*
G03X246582I600J800D01*
G02Y1198539I900J-1202D01*
G37*
G36*
G01X237759D02*
G03X236559I-600J-800D01*
G02Y1200943I-900J1202D01*
G03X237759I600J800D01*
G02Y1198539I900J-1202D01*
G37*
G36*
G01X230331D02*
G03X229131I-600J-800D01*
G02Y1200943I-900J1202D01*
G03X230331I600J800D01*
G02Y1198539I900J-1202D01*
G37*
G36*
G01X178800Y1197051D02*
G03X177600I-600J-800D01*
G02Y1199455I-900J1202D01*
G03X178800I600J800D01*
G02Y1197051I900J-1202D01*
G37*
G36*
G01X171304D02*
G03X170104I-600J-800D01*
G02Y1199455I-900J1202D01*
G03X171304I600J800D01*
G02Y1197051I900J-1202D01*
G37*
G36*
G01X162481D02*
G03X161281I-600J-800D01*
G02Y1199455I-900J1202D01*
G03X162481I600J800D01*
G02Y1197051I900J-1202D01*
G37*
G36*
G01X155053D02*
G03X153853I-600J-800D01*
G02Y1199455I-900J1202D01*
G03X155053I600J800D01*
G02Y1197051I900J-1202D01*
G37*
G36*
G01X178971Y1189133D02*
G03X177771I-600J-800D01*
G02Y1191537I-900J1202D01*
G03X178971I600J800D01*
G02Y1189133I900J-1202D01*
G37*
G36*
G01X171475D02*
G03X170275I-600J-800D01*
G02Y1191537I-900J1202D01*
G03X171475I600J800D01*
G02Y1189133I900J-1202D01*
G37*
G36*
G01X162652D02*
G03X161452I-600J-800D01*
G02Y1191537I-900J1202D01*
G03X162652I600J800D01*
G02Y1189133I900J-1202D01*
G37*
G36*
G01X155224D02*
G03X154024I-600J-800D01*
G02Y1191537I-900J1202D01*
G03X155224I600J800D01*
G02Y1189133I900J-1202D01*
G37*
G36*
G01X178971Y1182538D02*
G03X177771I-600J-800D01*
G02Y1184942I-900J1202D01*
G03X178971I600J800D01*
G02Y1182538I900J-1202D01*
G37*
G36*
G01X171475D02*
G03X170275I-600J-800D01*
G02Y1184942I-900J1202D01*
G03X171475I600J800D01*
G02Y1182538I900J-1202D01*
G37*
G36*
G01X162652D02*
G03X161452I-600J-800D01*
G02Y1184942I-900J1202D01*
G03X162652I600J800D01*
G02Y1182538I900J-1202D01*
G37*
G36*
G01X155224D02*
G03X154024I-600J-800D01*
G02Y1184942I-900J1202D01*
G03X155224I600J800D01*
G02Y1182538I900J-1202D01*
G37*
G36*
G01X178971Y1175054D02*
G03X177771I-600J-800D01*
G02Y1177458I-900J1202D01*
G03X178971I600J800D01*
G02Y1175054I900J-1202D01*
G37*
G36*
G01X171475D02*
G03X170275I-600J-800D01*
G02Y1177458I-900J1202D01*
G03X171475I600J800D01*
G02Y1175054I900J-1202D01*
G37*
G36*
G01X162652D02*
G03X161452I-600J-800D01*
G02Y1177458I-900J1202D01*
G03X162652I600J800D01*
G02Y1175054I900J-1202D01*
G37*
G36*
G01X155224D02*
G03X154024I-600J-800D01*
G02Y1177458I-900J1202D01*
G03X155224I600J800D01*
G02Y1175054I900J-1202D01*
G37*
G36*
G01X318516Y1171519D02*
Y1171302D01*
X318290D01*
X318165Y1171219D01*
G02X317114Y1170902I-1051J1584D01*
G01X312698D01*
G02Y1174706I0J1902D01*
G01X317114D01*
G02X318165Y1174389I0J-1901D01*
G01X318290Y1174306D01*
X318516D01*
Y1174089D01*
G02Y1171519I-1402J-1285D01*
G37*
G36*
G01X162652Y1167835D02*
G03X161452I-600J-800D01*
G02Y1170239I-900J1202D01*
G03X162652I600J800D01*
G02Y1167835I900J-1202D01*
G37*
G36*
G01X155224D02*
G03X154024I-600J-800D01*
G02Y1170239I-900J1202D01*
G03X155224I600J800D01*
G02Y1167835I900J-1202D01*
G37*
G36*
G01X325796Y1160264D02*
X320208D01*
G02X319008Y1160664I1J2002D01*
G01X318875Y1160764D01*
X318234D01*
X318108Y1160681D01*
G02X317058Y1160364I-1051J1585D01*
G01X312527D01*
G02Y1164168I0J1902D01*
G01X317058D01*
G02X318108Y1163851I-1J-1902D01*
G01X318234Y1163768D01*
X318875D01*
X319008Y1163868D01*
G02X320208Y1164268I1201J-1602D01*
G01X325796D01*
G02Y1160264I0J-2002D01*
G37*
G36*
G01X280956Y1130751D02*
Y1134471D01*
G02X284960I2002J0D01*
G01Y1130751D01*
G02X284879Y1130191I-2001J4D01*
G01X284860Y1130122D01*
Y1128650D01*
X281056D01*
Y1130122D01*
X281037Y1130191D01*
G02X280956Y1130751I1920J564D01*
G37*
G36*
G01X169982Y1077727D02*
G02X170003Y1077205I-6597J-527D01*
G02X156766I-6618J0D01*
G02X169982Y1077727I6618J0D01*
G37*
G36*
G01X180578Y1029337D02*
Y1029120D01*
X180353D01*
X180228Y1029037D01*
G02X179177Y1028720I-1051J1584D01*
G01X175804D01*
X174103Y1030421D01*
G02X176793Y1033111I1345J1345D01*
G01X177380Y1032524D01*
X179177D01*
G02X180228Y1032207I0J-1901D01*
G01X180353Y1032124D01*
X180578D01*
Y1031907D01*
G02Y1029337I-1401J-1285D01*
G37*
G36*
G01X182366Y1008428D02*
Y1008212D01*
X182141D01*
X182016Y1008128D01*
G02X180965Y1007812I-1050J1585D01*
G01X177676D01*
G03X177322Y1007665I0J-500D01*
G01X177043Y1007385D01*
G02X174353Y1010075I-1345J1345D01*
G01X175893Y1011614D01*
X180965D01*
G02X182016Y1011298I1J-1901D01*
G01X182141Y1011214D01*
X182366D01*
Y1010998D01*
G02Y1008428I-1401J-1285D01*
G37*
G36*
G01X257015Y1003466D02*
G03X255815I-600J-800D01*
G02Y1005870I-900J1202D01*
G03X257015I600J800D01*
G02Y1003466I900J-1202D01*
G37*
G36*
G01X249519D02*
G03X248319I-600J-800D01*
G02Y1005870I-900J1202D01*
G03X249519I600J800D01*
G02Y1003466I900J-1202D01*
G37*
G36*
G01X240696D02*
G03X239496I-600J-800D01*
G02Y1005870I-900J1202D01*
G03X240696I600J800D01*
G02Y1003466I900J-1202D01*
G37*
G36*
G01X233268D02*
G03X232068I-600J-800D01*
G02Y1005870I-900J1202D01*
G03X233268I600J800D01*
G02Y1003466I900J-1202D01*
G37*
G36*
G01X257015Y995947D02*
G03X255815I-600J-800D01*
G02Y998351I-900J1202D01*
G03X257015I600J800D01*
G02Y995947I900J-1202D01*
G37*
G36*
G01X249519D02*
G03X248319I-600J-800D01*
G02Y998351I-900J1202D01*
G03X249519I600J800D01*
G02Y995947I900J-1202D01*
G37*
G36*
G01X240696D02*
G03X239496I-600J-800D01*
G02Y998351I-900J1202D01*
G03X240696I600J800D01*
G02Y995947I900J-1202D01*
G37*
G36*
G01X233268D02*
G03X232068I-600J-800D01*
G02Y998351I-900J1202D01*
G03X233268I600J800D01*
G02Y995947I900J-1202D01*
G37*
G36*
G01X173548Y997636D02*
Y997660D01*
G02X176944Y998835I1901J0D01*
G01X176962Y998812D01*
X177315Y998460D01*
X181203D01*
G02X181300Y998457I-10J-1902D01*
G03X182352Y999456I52J999D01*
G01Y1001556D01*
G02X186354I2001J0D01*
G01Y996558D01*
G02X185755Y995130I-2002J0D01*
G01Y995056D01*
X185686D01*
X185553Y994956D01*
G02X183153I-1200J1602D01*
G01X183020Y995056D01*
X182379D01*
X182253Y994973D01*
G02X181203Y994656I-1051J1585D01*
G01X175739D01*
X174104Y996291D01*
G02X173548Y997636I1346J1344D01*
G37*
G36*
G01X182648Y989673D02*
Y989456D01*
X182423D01*
X182298Y989373D01*
G02X181247Y989056I-1051J1584D01*
G01X177530D01*
X177087Y988613D01*
G02X174397Y991303I-1345J1345D01*
G01X175954Y992860D01*
X181247D01*
G02X182298Y992543I0J-1901D01*
G01X182423Y992460D01*
X182648D01*
Y992243D01*
G02Y989673I-1401J-1285D01*
G37*
G36*
G01X257015Y987911D02*
G03X255815I-600J-800D01*
G02Y990315I-900J1202D01*
G03X257015I600J800D01*
G02Y987911I900J-1202D01*
G37*
G36*
G01X249519D02*
G03X248319I-600J-800D01*
G02Y990315I-900J1202D01*
G03X249519I600J800D01*
G02Y987911I900J-1202D01*
G37*
G36*
G01X240696D02*
G03X239496I-600J-800D01*
G02Y990315I-900J1202D01*
G03X240696I600J800D01*
G02Y987911I900J-1202D01*
G37*
G36*
G01X233268D02*
G03X232068I-600J-800D01*
G02Y990315I-900J1202D01*
G03X233268I600J800D01*
G02Y987911I900J-1202D01*
G37*
G36*
G01X257015Y980468D02*
G03X255815I-600J-800D01*
G02Y982872I-900J1202D01*
G03X257015I600J800D01*
G02Y980468I900J-1202D01*
G37*
G36*
G01X249519D02*
G03X248319I-600J-800D01*
G02Y982872I-900J1202D01*
G03X249519I600J800D01*
G02Y980468I900J-1202D01*
G37*
G36*
G01X240696D02*
G03X239496I-600J-800D01*
G02Y982872I-900J1202D01*
G03X240696I600J800D01*
G02Y980468I900J-1202D01*
G37*
G36*
G01X233268D02*
G03X232068I-600J-800D01*
G02Y982872I-900J1202D01*
G03X233268I600J800D01*
G02Y980468I900J-1202D01*
G37*
G36*
G01X181579Y981053D02*
G03X182630Y982052I51J999D01*
G01Y983423D01*
G02X186634I2002J0D01*
G01Y979154D01*
G02X186034Y977726I-2002J1D01*
G01Y977652D01*
X185965D01*
X185832Y977552D01*
G02X183432I-1200J1602D01*
G01X183299Y977652D01*
X182658D01*
X182532Y977569D01*
G02X181482Y977252I-1051J1585D01*
G01X175361D01*
X173677Y978936D01*
G02X176367Y981626I1345J1345D01*
G01X176937Y981056D01*
X181482D01*
G02X181579Y981053I-10J-1902D01*
G37*
G36*
G01X257186Y972550D02*
G03X255986I-600J-800D01*
G02Y974954I-900J1202D01*
G03X257186I600J800D01*
G02Y972550I900J-1202D01*
G37*
G36*
G01X249690D02*
G03X248490I-600J-800D01*
G02Y974954I-900J1202D01*
G03X249690I600J800D01*
G02Y972550I900J-1202D01*
G37*
G36*
G01X240867D02*
G03X239667I-600J-800D01*
G02Y974954I-900J1202D01*
G03X240867I600J800D01*
G02Y972550I900J-1202D01*
G37*
G36*
G01X233439D02*
G03X232239I-600J-800D01*
G02Y974954I-900J1202D01*
G03X233439I600J800D01*
G02Y972550I900J-1202D01*
G37*
G36*
G01X182790Y972269D02*
Y972052D01*
X182565D01*
X182440Y971969D01*
G02X181389Y971652I-1051J1584D01*
G01X176987D01*
X176480Y971145D01*
G02X173790Y973835I-1345J1345D01*
G01X175411Y975456D01*
X181389D01*
G02X182440Y975139I0J-1901D01*
G01X182565Y975056D01*
X182790D01*
Y974839D01*
G02Y972269I-1401J-1285D01*
G37*
G36*
G01X257186Y965955D02*
G03X255986I-600J-800D01*
G02Y968359I-900J1202D01*
G03X257186I600J800D01*
G02Y965955I900J-1202D01*
G37*
G36*
G01X249690D02*
G03X248490I-600J-800D01*
G02Y968359I-900J1202D01*
G03X249690I600J800D01*
G02Y965955I900J-1202D01*
G37*
G36*
G01X240867D02*
G03X239667I-600J-800D01*
G02Y968359I-900J1202D01*
G03X240867I600J800D01*
G02Y965955I900J-1202D01*
G37*
G36*
G01X233439D02*
G03X232239I-600J-800D01*
G02Y968359I-900J1202D01*
G03X233439I600J800D01*
G02Y965955I900J-1202D01*
G37*
G36*
G01X181143Y964570D02*
G03X182194Y965569I51J999D01*
G01Y967371D01*
G02X186198I2002J0D01*
G01Y962671D01*
G02X185598Y961243I-2002J1D01*
G01Y961169D01*
X185529D01*
X185396Y961069D01*
G02X182996I-1200J1602D01*
G01X182863Y961169D01*
X182222D01*
X182096Y961086D01*
G02X181046Y960770I-1050J1585D01*
G01X175386D01*
X174014Y962141D01*
G02X176704Y964831I1345J1345D01*
G01X176815Y964719D01*
G03X177170Y964572I354J353D01*
G01X181046D01*
G02X181143Y964570I9J-1901D01*
G37*
G36*
G01X257186Y958471D02*
G03X255986I-600J-800D01*
G02Y960875I-900J1202D01*
G03X257186I600J800D01*
G02Y958471I900J-1202D01*
G37*
G36*
G01X249690D02*
G03X248490I-600J-800D01*
G02Y960875I-900J1202D01*
G03X249690I600J800D01*
G02Y958471I900J-1202D01*
G37*
G36*
G01X240867D02*
G03X239667I-600J-800D01*
G02Y960875I-900J1202D01*
G03X240867I600J800D01*
G02Y958471I900J-1202D01*
G37*
G36*
G01X233439D02*
G03X232239I-600J-800D01*
G02Y960875I-900J1202D01*
G03X233439I600J800D01*
G02Y958471I900J-1202D01*
G37*
G36*
G01X182536Y955786D02*
Y955570D01*
X182311D01*
X182186Y955486D01*
G02X181135Y955170I-1050J1585D01*
G01X177663D01*
G03X177309Y955023I0J-500D01*
G01X176906Y954619D01*
G02X174216Y957309I-1345J1345D01*
G01X175880Y958972D01*
X181135D01*
G02X182186Y958656I1J-1901D01*
G01X182311Y958572D01*
X182536D01*
Y958356D01*
G02Y955786I-1401J-1285D01*
G37*
G36*
G01X283964Y955761D02*
Y959767D01*
G02X287968I2002J0D01*
G01Y955761D01*
G02X287887Y955201I-2001J4D01*
G01X287868Y955132D01*
Y953660D01*
X284064D01*
Y955132D01*
X284045Y955201D01*
G02X283964Y955761I1920J564D01*
G37*
G36*
G01X240867Y951252D02*
G03X239667I-600J-800D01*
G02Y953656I-900J1202D01*
G03X240867I600J800D01*
G02Y951252I900J-1202D01*
G37*
G36*
G01X233439D02*
G03X232239I-600J-800D01*
G02Y953656I-900J1202D01*
G03X233439I600J800D01*
G02Y951252I900J-1202D01*
G37*
G36*
G01X181231Y945478D02*
G03X182282Y946477I51J999D01*
G01Y948331D01*
G02X186286I2002J0D01*
G01Y943579D01*
G02X185686Y942151I-2002J1D01*
G01Y942077D01*
X185617D01*
X185484Y941977D01*
G02X183084I-1200J1602D01*
G01X182951Y942077D01*
X182310D01*
X182184Y941994D01*
G02X181134Y941678I-1050J1585D01*
G01X176159D01*
X174644Y943192D01*
G02X177334Y945882I1345J1345D01*
G01X177588Y945627D01*
G03X177942Y945480I354J353D01*
G01X181134D01*
G02X181231Y945478I9J-1901D01*
G37*
G36*
G01X182624Y936694D02*
Y936478D01*
X182399D01*
X182274Y936394D01*
G02X181223Y936078I-1050J1585D01*
G01X178156D01*
G03X177803Y935931I1J-500D01*
G01X177356Y935484D01*
G02X174666Y938174I-1345J1345D01*
G01X176373Y939880D01*
X181223D01*
G02X182274Y939564I1J-1901D01*
G01X182399Y939480D01*
X182624D01*
Y939264D01*
G02Y936694I-1401J-1285D01*
G37*
G36*
G01X169982Y902727D02*
G02X170003Y902205I-6597J-527D01*
G02X156766I-6618J0D01*
G02X169982Y902727I6618J0D01*
G37*
G36*
G01X181120Y866518D02*
G03X179920I-600J-800D01*
G02Y868922I-900J1202D01*
G03X181120I600J800D01*
G02Y866518I900J-1202D01*
G37*
G36*
G01X173624D02*
G03X172424I-600J-800D01*
G02Y868922I-900J1202D01*
G03X173624I600J800D01*
G02Y866518I900J-1202D01*
G37*
G36*
G01X164801D02*
G03X163601I-600J-800D01*
G02Y868922I-900J1202D01*
G03X164801I600J800D01*
G02Y866518I900J-1202D01*
G37*
G36*
G01X157373D02*
G03X156173I-600J-800D01*
G02Y868922I-900J1202D01*
G03X157373I600J800D01*
G02Y866518I900J-1202D01*
G37*
G36*
G01X181120Y858999D02*
G03X179920I-600J-800D01*
G02Y861403I-900J1202D01*
G03X181120I600J800D01*
G02Y858999I900J-1202D01*
G37*
G36*
G01X173624D02*
G03X172424I-600J-800D01*
G02Y861403I-900J1202D01*
G03X173624I600J800D01*
G02Y858999I900J-1202D01*
G37*
G36*
G01X164801D02*
G03X163601I-600J-800D01*
G02Y861403I-900J1202D01*
G03X164801I600J800D01*
G02Y858999I900J-1202D01*
G37*
G36*
G01X157373D02*
G03X156173I-600J-800D01*
G02Y861403I-900J1202D01*
G03X157373I600J800D01*
G02Y858999I900J-1202D01*
G37*
G36*
G01X181120Y850963D02*
G03X179920I-600J-800D01*
G02Y853367I-900J1202D01*
G03X181120I600J800D01*
G02Y850963I900J-1202D01*
G37*
G36*
G01X173624D02*
G03X172424I-600J-800D01*
G02Y853367I-900J1202D01*
G03X173624I600J800D01*
G02Y850963I900J-1202D01*
G37*
G36*
G01X164801D02*
G03X163601I-600J-800D01*
G02Y853367I-900J1202D01*
G03X164801I600J800D01*
G02Y850963I900J-1202D01*
G37*
G36*
G01X157373D02*
G03X156173I-600J-800D01*
G02Y853367I-900J1202D01*
G03X157373I600J800D01*
G02Y850963I900J-1202D01*
G37*
G36*
G01X181120Y843520D02*
G03X179920I-600J-800D01*
G02Y845924I-900J1202D01*
G03X181120I600J800D01*
G02Y843520I900J-1202D01*
G37*
G36*
G01X173624D02*
G03X172424I-600J-800D01*
G02Y845924I-900J1202D01*
G03X173624I600J800D01*
G02Y843520I900J-1202D01*
G37*
G36*
G01X164801D02*
G03X163601I-600J-800D01*
G02Y845924I-900J1202D01*
G03X164801I600J800D01*
G02Y843520I900J-1202D01*
G37*
G36*
G01X157373D02*
G03X156173I-600J-800D01*
G02Y845924I-900J1202D01*
G03X157373I600J800D01*
G02Y843520I900J-1202D01*
G37*
G36*
G01X181291Y835602D02*
G03X180091I-600J-800D01*
G02Y838006I-900J1202D01*
G03X181291I600J800D01*
G02Y835602I900J-1202D01*
G37*
G36*
G01X173795D02*
G03X172595I-600J-800D01*
G02Y838006I-900J1202D01*
G03X173795I600J800D01*
G02Y835602I900J-1202D01*
G37*
G36*
G01X164972D02*
G03X163772I-600J-800D01*
G02Y838006I-900J1202D01*
G03X164972I600J800D01*
G02Y835602I900J-1202D01*
G37*
G36*
G01X157544D02*
G03X156344I-600J-800D01*
G02Y838006I-900J1202D01*
G03X157544I600J800D01*
G02Y835602I900J-1202D01*
G37*
G36*
G01X181291Y829007D02*
G03X180091I-600J-800D01*
G02Y831411I-900J1202D01*
G03X181291I600J800D01*
G02Y829007I900J-1202D01*
G37*
G36*
G01X173795D02*
G03X172595I-600J-800D01*
G02Y831411I-900J1202D01*
G03X173795I600J800D01*
G02Y829007I900J-1202D01*
G37*
G36*
G01X164972D02*
G03X163772I-600J-800D01*
G02Y831411I-900J1202D01*
G03X164972I600J800D01*
G02Y829007I900J-1202D01*
G37*
G36*
G01X157544D02*
G03X156344I-600J-800D01*
G02Y831411I-900J1202D01*
G03X157544I600J800D01*
G02Y829007I900J-1202D01*
G37*
G36*
G01X262426Y822319D02*
Y822102D01*
X262201D01*
X262076Y822019D01*
G02X260768Y821720I-1051J1585D01*
G01X260735Y821724D01*
X255837D01*
G02Y825528I0J1902D01*
G01X261791D01*
X262213Y825106D01*
X262426D01*
Y824889D01*
G02Y822319I-1401J-1285D01*
G37*
G36*
G01X181291Y821523D02*
G03X180091I-600J-800D01*
G02Y823927I-900J1202D01*
G03X181291I600J800D01*
G02Y821523I900J-1202D01*
G37*
G36*
G01X173795D02*
G03X172595I-600J-800D01*
G02Y823927I-900J1202D01*
G03X173795I600J800D01*
G02Y821523I900J-1202D01*
G37*
G36*
G01X164972D02*
G03X163772I-600J-800D01*
G02Y823927I-900J1202D01*
G03X164972I600J800D01*
G02Y821523I900J-1202D01*
G37*
G36*
G01X157544D02*
G03X156344I-600J-800D01*
G02Y823927I-900J1202D01*
G03X157544I600J800D01*
G02Y821523I900J-1202D01*
G37*
G36*
G01X260928Y810286D02*
X260895Y810290D01*
X255687D01*
G02Y814094I0J1902D01*
G01X261951D01*
X262225Y813819D01*
G03X262579Y813672I354J353D01*
G01X263159D01*
X263285Y813755D01*
G02X264335Y814072I1051J-1585D01*
G01X269780D01*
X269813Y814076D01*
G02X271415Y810847I257J-1884D01*
G01X270836Y810268D01*
X264335D01*
G02X263285Y810585I1J1902D01*
G01X263159Y810668D01*
X262361D01*
X262235Y810585D01*
G02X260928Y810286I-1050J1585D01*
G37*
G36*
G01X271112Y782036D02*
Y785968D01*
G02X275116I2002J0D01*
G01Y782036D01*
G02X275035Y781476I-2001J4D01*
G01X275016Y781407D01*
Y779934D01*
X271212D01*
Y781407D01*
X271193Y781476D01*
G02X271112Y782036I1920J564D01*
G37*
G36*
G01X253639Y637822D02*
G03X252439I-600J-800D01*
G02Y640226I-900J1202D01*
G03X253639I600J800D01*
G02Y637822I900J-1202D01*
G37*
G36*
G01X246143D02*
G03X244943I-600J-800D01*
G02Y640226I-900J1202D01*
G03X246143I600J800D01*
G02Y637822I900J-1202D01*
G37*
G36*
G01X237320D02*
G03X236120I-600J-800D01*
G02Y640226I-900J1202D01*
G03X237320I600J800D01*
G02Y637822I900J-1202D01*
G37*
G36*
G01X229892D02*
G03X228692I-600J-800D01*
G02Y640226I-900J1202D01*
G03X229892I600J800D01*
G02Y637822I900J-1202D01*
G37*
G36*
G01X253639Y630303D02*
G03X252439I-600J-800D01*
G02Y632707I-900J1202D01*
G03X253639I600J800D01*
G02Y630303I900J-1202D01*
G37*
G36*
G01X246143D02*
G03X244943I-600J-800D01*
G02Y632707I-900J1202D01*
G03X246143I600J800D01*
G02Y630303I900J-1202D01*
G37*
G36*
G01X237320D02*
G03X236120I-600J-800D01*
G02Y632707I-900J1202D01*
G03X237320I600J800D01*
G02Y630303I900J-1202D01*
G37*
G36*
G01X229892D02*
G03X228692I-600J-800D01*
G02Y632707I-900J1202D01*
G03X229892I600J800D01*
G02Y630303I900J-1202D01*
G37*
G36*
G01X278144Y623425D02*
G03X276944I-600J-800D01*
G02Y625829I-900J1202D01*
G03X278144I600J800D01*
G02Y623425I900J-1202D01*
G37*
G36*
G01X266533Y623119D02*
G03X265333I-600J-800D01*
G02Y625523I-900J1202D01*
G03X266533I600J800D01*
G02Y623119I900J-1202D01*
G37*
G36*
G01X253639Y622267D02*
G03X252439I-600J-800D01*
G02Y624671I-900J1202D01*
G03X253639I600J800D01*
G02Y622267I900J-1202D01*
G37*
G36*
G01X246143D02*
G03X244943I-600J-800D01*
G02Y624671I-900J1202D01*
G03X246143I600J800D01*
G02Y622267I900J-1202D01*
G37*
G36*
G01X237320D02*
G03X236120I-600J-800D01*
G02Y624671I-900J1202D01*
G03X237320I600J800D01*
G02Y622267I900J-1202D01*
G37*
G36*
G01X229892D02*
G03X228692I-600J-800D01*
G02Y624671I-900J1202D01*
G03X229892I600J800D01*
G02Y622267I900J-1202D01*
G37*
G36*
G01X253639Y614824D02*
G03X252439I-600J-800D01*
G02Y617228I-900J1202D01*
G03X253639I600J800D01*
G02Y614824I900J-1202D01*
G37*
G36*
G01X246143D02*
G03X244943I-600J-800D01*
G02Y617228I-900J1202D01*
G03X246143I600J800D01*
G02Y614824I900J-1202D01*
G37*
G36*
G01X237320D02*
G03X236120I-600J-800D01*
G02Y617228I-900J1202D01*
G03X237320I600J800D01*
G02Y614824I900J-1202D01*
G37*
G36*
G01X229892D02*
G03X228692I-600J-800D01*
G02Y617228I-900J1202D01*
G03X229892I600J800D01*
G02Y614824I900J-1202D01*
G37*
G36*
G01X253810Y606906D02*
G03X252610I-600J-800D01*
G02Y609310I-900J1202D01*
G03X253810I600J800D01*
G02Y606906I900J-1202D01*
G37*
G36*
G01X246314D02*
G03X245114I-600J-800D01*
G02Y609310I-900J1202D01*
G03X246314I600J800D01*
G02Y606906I900J-1202D01*
G37*
G36*
G01X237491D02*
G03X236291I-600J-800D01*
G02Y609310I-900J1202D01*
G03X237491I600J800D01*
G02Y606906I900J-1202D01*
G37*
G36*
G01X230063D02*
G03X228863I-600J-800D01*
G02Y609310I-900J1202D01*
G03X230063I600J800D01*
G02Y606906I900J-1202D01*
G37*
G36*
G01X283346Y606962D02*
Y610540D01*
G02X287350I2002J0D01*
G01Y606962D01*
G02X287269Y606402I-2001J4D01*
G01X287250Y606333D01*
Y604860D01*
X283446D01*
Y606333D01*
X283427Y606402D01*
G02X283346Y606962I1920J564D01*
G37*
G36*
G01X253810Y600311D02*
G03X252610I-600J-800D01*
G02Y602715I-900J1202D01*
G03X253810I600J800D01*
G02Y600311I900J-1202D01*
G37*
G36*
G01X246314D02*
G03X245114I-600J-800D01*
G02Y602715I-900J1202D01*
G03X246314I600J800D01*
G02Y600311I900J-1202D01*
G37*
G36*
G01X237491D02*
G03X236291I-600J-800D01*
G02Y602715I-900J1202D01*
G03X237491I600J800D01*
G02Y600311I900J-1202D01*
G37*
G36*
G01X230063D02*
G03X228863I-600J-800D01*
G02Y602715I-900J1202D01*
G03X230063I600J800D01*
G02Y600311I900J-1202D01*
G37*
G36*
G01X253810Y592827D02*
G03X252610I-600J-800D01*
G02Y595231I-900J1202D01*
G03X253810I600J800D01*
G02Y592827I900J-1202D01*
G37*
G36*
G01X246314D02*
G03X245114I-600J-800D01*
G02Y595231I-900J1202D01*
G03X246314I600J800D01*
G02Y592827I900J-1202D01*
G37*
G36*
G01X237491D02*
G03X236291I-600J-800D01*
G02Y595231I-900J1202D01*
G03X237491I600J800D01*
G02Y592827I900J-1202D01*
G37*
G36*
G01X230063D02*
G03X228863I-600J-800D01*
G02Y595231I-900J1202D01*
G03X230063I600J800D01*
G02Y592827I900J-1202D01*
G37*
G36*
G01X158359Y512726D02*
G03X157159I-600J-800D01*
G02Y515130I-900J1202D01*
G03X158359I600J800D01*
G02Y512726I900J-1202D01*
G37*
G36*
G01X247796Y512095D02*
G03X246596I-600J-800D01*
G02Y514499I-900J1202D01*
G03X247796I600J800D01*
G02Y512095I900J-1202D01*
G37*
G36*
G01X240300D02*
G03X239100I-600J-800D01*
G02Y514499I-900J1202D01*
G03X240300I600J800D01*
G02Y512095I900J-1202D01*
G37*
G36*
G01X231477D02*
G03X230277I-600J-800D01*
G02Y514499I-900J1202D01*
G03X231477I600J800D01*
G02Y512095I900J-1202D01*
G37*
G36*
G01X158359Y505207D02*
G03X157159I-600J-800D01*
G02Y507611I-900J1202D01*
G03X158359I600J800D01*
G02Y505207I900J-1202D01*
G37*
G36*
G01X247796Y504576D02*
G03X246596I-600J-800D01*
G02Y506980I-900J1202D01*
G03X247796I600J800D01*
G02Y504576I900J-1202D01*
G37*
G36*
G01X240300D02*
G03X239100I-600J-800D01*
G02Y506980I-900J1202D01*
G03X240300I600J800D01*
G02Y504576I900J-1202D01*
G37*
G36*
G01X231477D02*
G03X230277I-600J-800D01*
G02Y506980I-900J1202D01*
G03X231477I600J800D01*
G02Y504576I900J-1202D01*
G37*
G36*
G01X158359Y497171D02*
G03X157159I-600J-800D01*
G02Y499575I-900J1202D01*
G03X158359I600J800D01*
G02Y497171I900J-1202D01*
G37*
G36*
G01X247796Y496540D02*
G03X246596I-600J-800D01*
G02Y498944I-900J1202D01*
G03X247796I600J800D01*
G02Y496540I900J-1202D01*
G37*
G36*
G01X240300D02*
G03X239100I-600J-800D01*
G02Y498944I-900J1202D01*
G03X240300I600J800D01*
G02Y496540I900J-1202D01*
G37*
G36*
G01X231477D02*
G03X230277I-600J-800D01*
G02Y498944I-900J1202D01*
G03X231477I600J800D01*
G02Y496540I900J-1202D01*
G37*
G36*
G01X158359Y489728D02*
G03X157159I-600J-800D01*
G02Y492132I-900J1202D01*
G03X158359I600J800D01*
G02Y489728I900J-1202D01*
G37*
G36*
G01X247796Y489097D02*
G03X246596I-600J-800D01*
G02Y491501I-900J1202D01*
G03X247796I600J800D01*
G02Y489097I900J-1202D01*
G37*
G36*
G01X240300D02*
G03X239100I-600J-800D01*
G02Y491501I-900J1202D01*
G03X240300I600J800D01*
G02Y489097I900J-1202D01*
G37*
G36*
G01X231477D02*
G03X230277I-600J-800D01*
G02Y491501I-900J1202D01*
G03X231477I600J800D01*
G02Y489097I900J-1202D01*
G37*
G36*
G01X158530Y481810D02*
G03X157330I-600J-800D01*
G02Y484214I-900J1202D01*
G03X158530I600J800D01*
G02Y481810I900J-1202D01*
G37*
G36*
G01X247967Y481179D02*
G03X246767I-600J-800D01*
G02Y483583I-900J1202D01*
G03X247967I600J800D01*
G02Y481179I900J-1202D01*
G37*
G36*
G01X240471D02*
G03X239271I-600J-800D01*
G02Y483583I-900J1202D01*
G03X240471I600J800D01*
G02Y481179I900J-1202D01*
G37*
G36*
G01X231648D02*
G03X230448I-600J-800D01*
G02Y483583I-900J1202D01*
G03X231648I600J800D01*
G02Y481179I900J-1202D01*
G37*
G36*
G01X158530Y475215D02*
G03X157330I-600J-800D01*
G02Y477619I-900J1202D01*
G03X158530I600J800D01*
G02Y475215I900J-1202D01*
G37*
G36*
G01X247967Y474584D02*
G03X246767I-600J-800D01*
G02Y476988I-900J1202D01*
G03X247967I600J800D01*
G02Y474584I900J-1202D01*
G37*
G36*
G01X240471D02*
G03X239271I-600J-800D01*
G02Y476988I-900J1202D01*
G03X240471I600J800D01*
G02Y474584I900J-1202D01*
G37*
G36*
G01X231648D02*
G03X230448I-600J-800D01*
G02Y476988I-900J1202D01*
G03X231648I600J800D01*
G02Y474584I900J-1202D01*
G37*
G36*
G01X268793Y471778D02*
X265737D01*
G02Y475582I0J1902D01*
G01X269673D01*
X269929Y475325D01*
G03X270283Y475178I354J353D01*
G01X270290D01*
Y474962D01*
G02Y472392I-1402J-1285D01*
G01Y472176D01*
X270064D01*
X269939Y472092D01*
G02X268793Y471778I-1050J1585D01*
G37*
G36*
G01X158530Y467731D02*
G03X157330I-600J-800D01*
G02Y470135I-900J1202D01*
G03X158530I600J800D01*
G02Y467731I900J-1202D01*
G37*
G36*
G01X247967Y467100D02*
G03X246767I-600J-800D01*
G02Y469504I-900J1202D01*
G03X247967I600J800D01*
G02Y467100I900J-1202D01*
G37*
G36*
G01X240471D02*
G03X239271I-600J-800D01*
G02Y469504I-900J1202D01*
G03X240471I600J800D01*
G02Y467100I900J-1202D01*
G37*
G36*
G01X231648D02*
G03X230448I-600J-800D01*
G02Y469504I-900J1202D01*
G03X231648I600J800D01*
G02Y467100I900J-1202D01*
G37*
G36*
G01X268866Y461200D02*
X265722D01*
G02Y465004I0J1902D01*
G01X269746D01*
X270001Y464748D01*
G03X270355Y464601I354J353D01*
G01X270935D01*
X271061Y464684D01*
G02X272111Y465000I1050J-1585D01*
G01X274991D01*
G02Y461198I0J-1901D01*
G01X272111D01*
G02X271061Y461514I0J1901D01*
G01X270935Y461597D01*
X270137D01*
X270011Y461514D01*
G02X268866Y461200I-1050J1585D01*
G37*
G36*
G01X158530Y460512D02*
G03X157330I-600J-800D01*
G02Y462916I-900J1202D01*
G03X158530I600J800D01*
G02Y460512I900J-1202D01*
G37*
G36*
G01X231648Y459881D02*
G03X230448I-600J-800D01*
G02Y462285I-900J1202D01*
G03X231648I600J800D01*
G02Y459881I900J-1202D01*
G37*
G36*
G01X158807Y431068D02*
X155348D01*
G02X154187Y431463I-1J1901D01*
G01X154052Y431567D01*
X153846D01*
Y431793D01*
X153763Y431919D01*
G02X153453Y433121I1585J1050D01*
G03X152456Y434200I-997J79D01*
G01X143368D01*
G03X142957Y433986I-1J-500D01*
G02Y438218I-3037J2116D01*
G03X143368Y438004I410J286D01*
G01X152462D01*
G03X153457Y439095I-1J1000D01*
G02X153766Y440318I1894J172D01*
G01X153849Y440444D01*
Y440670D01*
X154055D01*
X154190Y440774D01*
G02X155351Y441170I1162J-1506D01*
G01X159019D01*
G02Y437366I0J-1902D01*
G01X158239D01*
G03X157243Y436281I0J-1000D01*
G02Y435956I-1895J-162D01*
G03X158239Y434870I996J-86D01*
G01X158807D01*
G02Y431068I0J-1901D01*
G37*
G36*
G01X279568Y432340D02*
Y436169D01*
G02X283570I2001J0D01*
G01Y432340D01*
G02X283490Y431780I-2000J0D01*
G01X283470Y431711D01*
Y430238D01*
X279668D01*
Y431711D01*
X279648Y431780D01*
G02X279568Y432340I1920J560D01*
G37*
G36*
G01X116575Y394515D02*
X116513Y394645D01*
X116269Y394800D01*
X115031D01*
X114956Y394777D01*
G02X115295Y397480I-458J1430D01*
G01X115417Y397404D01*
X116269D01*
X116513Y397559D01*
X116575Y397689D01*
G02Y394515I3345J-1587D01*
G37*
G36*
G01X169982Y377727D02*
G02X170002Y377205I-6597J-514D01*
G02X156766I-6618J0D01*
G02X169982Y377727I6618J0D01*
G37*
G36*
G01X176962Y312606D02*
G03X175762I-600J-800D01*
G02Y315010I-900J1202D01*
G03X176962I600J800D01*
G02Y312606I900J-1202D01*
G37*
G36*
G01Y305087D02*
G03X175762I-600J-800D01*
G02Y307491I-900J1202D01*
G03X176962I600J800D01*
G02Y305087I900J-1202D01*
G37*
G36*
G01Y297051D02*
G03X175762I-600J-800D01*
G02Y299455I-900J1202D01*
G03X176962I600J800D01*
G02Y297051I900J-1202D01*
G37*
G36*
G01Y289608D02*
G03X175762I-600J-800D01*
G02Y292012I-900J1202D01*
G03X176962I600J800D01*
G02Y289608I900J-1202D01*
G37*
G36*
G01X242962Y288788D02*
G03X241762I-600J-800D01*
G02Y291192I-900J1202D01*
G03X242962I600J800D01*
G02Y288788I900J-1202D01*
G37*
G36*
G01X235466D02*
G03X234266I-600J-800D01*
G02Y291192I-900J1202D01*
G03X235466I600J800D01*
G02Y288788I900J-1202D01*
G37*
G36*
G01X226643D02*
G03X225443I-600J-800D01*
G02Y291192I-900J1202D01*
G03X226643I600J800D01*
G02Y288788I900J-1202D01*
G37*
G36*
G01X177133Y281690D02*
G03X175933I-600J-800D01*
G02Y284094I-900J1202D01*
G03X177133I600J800D01*
G02Y281690I900J-1202D01*
G37*
G36*
G01X242962Y281269D02*
G03X241762I-600J-800D01*
G02Y283673I-900J1202D01*
G03X242962I600J800D01*
G02Y281269I900J-1202D01*
G37*
G36*
G01X235466D02*
G03X234266I-600J-800D01*
G02Y283673I-900J1202D01*
G03X235466I600J800D01*
G02Y281269I900J-1202D01*
G37*
G36*
G01X226643D02*
G03X225443I-600J-800D01*
G02Y283673I-900J1202D01*
G03X226643I600J800D01*
G02Y281269I900J-1202D01*
G37*
G36*
G01X177133Y275095D02*
G03X175933I-600J-800D01*
G02Y277499I-900J1202D01*
G03X177133I600J800D01*
G02Y275095I900J-1202D01*
G37*
G36*
G01X242962Y273233D02*
G03X241762I-600J-800D01*
G02Y275637I-900J1202D01*
G03X242962I600J800D01*
G02Y273233I900J-1202D01*
G37*
G36*
G01X235466D02*
G03X234266I-600J-800D01*
G02Y275637I-900J1202D01*
G03X235466I600J800D01*
G02Y273233I900J-1202D01*
G37*
G36*
G01X226643D02*
G03X225443I-600J-800D01*
G02Y275637I-900J1202D01*
G03X226643I600J800D01*
G02Y273233I900J-1202D01*
G37*
G36*
G01X177133Y267611D02*
G03X175933I-600J-800D01*
G02Y270015I-900J1202D01*
G03X177133I600J800D01*
G02Y267611I900J-1202D01*
G37*
G36*
G01X242962Y265790D02*
G03X241762I-600J-800D01*
G02Y268194I-900J1202D01*
G03X242962I600J800D01*
G02Y265790I900J-1202D01*
G37*
G36*
G01X235466D02*
G03X234266I-600J-800D01*
G02Y268194I-900J1202D01*
G03X235466I600J800D01*
G02Y265790I900J-1202D01*
G37*
G36*
G01X226643D02*
G03X225443I-600J-800D01*
G02Y268194I-900J1202D01*
G03X226643I600J800D01*
G02Y265790I900J-1202D01*
G37*
G36*
G01X177133Y260392D02*
G03X175933I-600J-800D01*
G02Y262796I-900J1202D01*
G03X177133I600J800D01*
G02Y260392I900J-1202D01*
G37*
G36*
G01X243133Y257872D02*
G03X241933I-600J-800D01*
G02Y260276I-900J1202D01*
G03X243133I600J800D01*
G02Y257872I900J-1202D01*
G37*
G36*
G01X235637D02*
G03X234437I-600J-800D01*
G02Y260276I-900J1202D01*
G03X235637I600J800D01*
G02Y257872I900J-1202D01*
G37*
G36*
G01X226814D02*
G03X225614I-600J-800D01*
G02Y260276I-900J1202D01*
G03X226814I600J800D01*
G02Y257872I900J-1202D01*
G37*
G36*
G01X269546Y256764D02*
Y260353D01*
G02X273548I2001J0D01*
G01Y256764D01*
G02X273468Y256204I-2000J0D01*
G01X273448Y256135D01*
Y254662D01*
X269646D01*
Y256135D01*
X269626Y256204D01*
G02X269546Y256764I1920J560D01*
G37*
G36*
G01X243133Y251277D02*
G03X241933I-600J-800D01*
G02Y253681I-900J1202D01*
G03X243133I600J800D01*
G02Y251277I900J-1202D01*
G37*
G36*
G01X235637D02*
G03X234437I-600J-800D01*
G02Y253681I-900J1202D01*
G03X235637I600J800D01*
G02Y251277I900J-1202D01*
G37*
G36*
G01X226814D02*
G03X225614I-600J-800D01*
G02Y253681I-900J1202D01*
G03X226814I600J800D01*
G02Y251277I900J-1202D01*
G37*
G36*
G01X243133Y243793D02*
G03X241933I-600J-800D01*
G02Y246197I-900J1202D01*
G03X243133I600J800D01*
G02Y243793I900J-1202D01*
G37*
G36*
G01X235637D02*
G03X234437I-600J-800D01*
G02Y246197I-900J1202D01*
G03X235637I600J800D01*
G02Y243793I900J-1202D01*
G37*
G36*
G01X226814D02*
G03X225614I-600J-800D01*
G02Y246197I-900J1202D01*
G03X226814I600J800D01*
G02Y243793I900J-1202D01*
G37*
G36*
G01Y236574D02*
G03X225614I-600J-800D01*
G02Y238978I-900J1202D01*
G03X226814I600J800D01*
G02Y236574I900J-1202D01*
G37*
G36*
G01X169982Y202727D02*
G02X170002Y202205I-6597J-514D01*
G02X156766I-6618J0D01*
G02X169982Y202727I6618J0D01*
G37*
G36*
G01X175857Y162419D02*
G03X174657I-600J-800D01*
G02Y164823I-900J1202D01*
G03X175857I600J800D01*
G02Y162419I900J-1202D01*
G37*
G36*
G01X168429D02*
G03X167229I-600J-800D01*
G02Y164823I-900J1202D01*
G03X168429I600J800D01*
G02Y162419I900J-1202D01*
G37*
G36*
G01X175857Y154900D02*
G03X174657I-600J-800D01*
G02Y157304I-900J1202D01*
G03X175857I600J800D01*
G02Y154900I900J-1202D01*
G37*
G36*
G01X168429D02*
G03X167229I-600J-800D01*
G02Y157304I-900J1202D01*
G03X168429I600J800D01*
G02Y154900I900J-1202D01*
G37*
G36*
G01X175857Y146864D02*
G03X174657I-600J-800D01*
G02Y149268I-900J1202D01*
G03X175857I600J800D01*
G02Y146864I900J-1202D01*
G37*
G36*
G01X168429D02*
G03X167229I-600J-800D01*
G02Y149268I-900J1202D01*
G03X168429I600J800D01*
G02Y146864I900J-1202D01*
G37*
G36*
G01X175857Y139421D02*
G03X174657I-600J-800D01*
G02Y141825I-900J1202D01*
G03X175857I600J800D01*
G02Y139421I900J-1202D01*
G37*
G36*
G01X168429D02*
G03X167229I-600J-800D01*
G02Y141825I-900J1202D01*
G03X168429I600J800D01*
G02Y139421I900J-1202D01*
G37*
G36*
G01X176028Y131503D02*
G03X174828I-600J-800D01*
G02Y133907I-900J1202D01*
G03X176028I600J800D01*
G02Y131503I900J-1202D01*
G37*
G36*
G01X168600D02*
G03X167400I-600J-800D01*
G02Y133907I-900J1202D01*
G03X168600I600J800D01*
G02Y131503I900J-1202D01*
G37*
G36*
G01X261157Y126365D02*
X261107Y126374D01*
X256947D01*
G02Y130178I0J1902D01*
G01X262275D01*
X262723Y129730D01*
X262936D01*
Y129513D01*
G02Y126943I-1401J-1285D01*
G01Y126726D01*
X262711D01*
X262586Y126643D01*
G02X261157Y126365I-1050J1585D01*
G37*
G36*
G01X176028Y124908D02*
G03X174828I-600J-800D01*
G02Y127312I-900J1202D01*
G03X176028I600J800D01*
G02Y124908I900J-1202D01*
G37*
G36*
G01X168600D02*
G03X167400I-600J-800D01*
G02Y127312I-900J1202D01*
G03X168600I600J800D01*
G02Y124908I900J-1202D01*
G37*
G36*
G01X176028Y117424D02*
G03X174828I-600J-800D01*
G02Y119828I-900J1202D01*
G03X176028I600J800D01*
G02Y117424I900J-1202D01*
G37*
G36*
G01X168600D02*
G03X167400I-600J-800D01*
G02Y119828I-900J1202D01*
G03X168600I600J800D01*
G02Y117424I900J-1202D01*
G37*
G36*
G01X261779Y113658D02*
X257125D01*
G02Y117460I0J1901D01*
G01X261779D01*
G02X262829Y117144I0J-1901D01*
G01X262955Y117061D01*
X263753D01*
X263879Y117144D01*
G02X264929Y117460I1050J-1585D01*
G01X267627D01*
G02Y113658I0J-1901D01*
G01X264929D01*
G02X263879Y113974I0J1901D01*
G01X263753Y114057D01*
X262955D01*
X262829Y113974D01*
G02X261779Y113658I-1050J1585D01*
G37*
G36*
G01X176028Y110205D02*
G03X174828I-600J-800D01*
G02Y112609I-900J1202D01*
G03X176028I600J800D01*
G02Y110205I900J-1202D01*
G37*
G36*
G01X168600D02*
G03X167400I-600J-800D01*
G02Y112609I-900J1202D01*
G03X168600I600J800D01*
G02Y110205I900J-1202D01*
G37*
G36*
G01X247380Y100792D02*
G03X246180I-600J-800D01*
G02Y103196I-900J1202D01*
G03X247380I600J800D01*
G02Y100792I900J-1202D01*
G37*
G36*
G01X239884D02*
G03X238684I-600J-800D01*
G02Y103196I-900J1202D01*
G03X239884I600J800D01*
G02Y100792I900J-1202D01*
G37*
G36*
G01X247380Y93273D02*
G03X246180I-600J-800D01*
G02Y95677I-900J1202D01*
G03X247380I600J800D01*
G02Y93273I900J-1202D01*
G37*
G36*
G01X239884D02*
G03X238684I-600J-800D01*
G02Y95677I-900J1202D01*
G03X239884I600J800D01*
G02Y93273I900J-1202D01*
G37*
G36*
G01X247380Y85237D02*
G03X246180I-600J-800D01*
G02Y87641I-900J1202D01*
G03X247380I600J800D01*
G02Y85237I900J-1202D01*
G37*
G36*
G01X239884D02*
G03X238684I-600J-800D01*
G02Y87641I-900J1202D01*
G03X239884I600J800D01*
G02Y85237I900J-1202D01*
G37*
G36*
G01X247380Y77794D02*
G03X246180I-600J-800D01*
G02Y80198I-900J1202D01*
G03X247380I600J800D01*
G02Y77794I900J-1202D01*
G37*
G36*
G01X239884D02*
G03X238684I-600J-800D01*
G02Y80198I-900J1202D01*
G03X239884I600J800D01*
G02Y77794I900J-1202D01*
G37*
G36*
G01X292482Y78718D02*
Y82732D01*
G02X296484I2001J0D01*
G01Y78718D01*
G02X296404Y78158I-2000J0D01*
G01X296384Y78089D01*
Y76616D01*
X292582D01*
Y78089D01*
X292562Y78158D01*
G02X292482Y78718I1920J560D01*
G37*
G36*
G01X247551Y69876D02*
G03X246351I-600J-800D01*
G02Y72280I-900J1202D01*
G03X247551I600J800D01*
G02Y69876I900J-1202D01*
G37*
G36*
G01X240055D02*
G03X238855I-600J-800D01*
G02Y72280I-900J1202D01*
G03X240055I600J800D01*
G02Y69876I900J-1202D01*
G37*
G36*
G01X247551Y63281D02*
G03X246351I-600J-800D01*
G02Y65685I-900J1202D01*
G03X247551I600J800D01*
G02Y63281I900J-1202D01*
G37*
G36*
G01X240055D02*
G03X238855I-600J-800D01*
G02Y65685I-900J1202D01*
G03X240055I600J800D01*
G02Y63281I900J-1202D01*
G37*
G36*
G01X247551Y55797D02*
G03X246351I-600J-800D01*
G02Y58201I-900J1202D01*
G03X247551I600J800D01*
G02Y55797I900J-1202D01*
G37*
G36*
G01X240055D02*
G03X238855I-600J-800D01*
G02Y58201I-900J1202D01*
G03X240055I600J800D01*
G02Y55797I900J-1202D01*
G37*
G36*
G01X156206Y52081D02*
X156256Y52184D01*
Y52687D01*
X155224Y53719D01*
Y55242D01*
X155124D01*
Y58246D01*
X158343D01*
X158476Y58346D01*
G02X159676Y58746I1201J-1602D01*
G01X162384D01*
G02Y54742I0J-2002D01*
G01X159676D01*
G02X159131Y54818I1J2002D01*
G01X159000Y54855D01*
X158738Y54787D01*
X158642Y54691D01*
G03Y53983I353J-354D01*
G01X158860Y53765D01*
Y52184D01*
X158910Y52081D01*
G02X158050Y50007I-1352J-655D01*
G01X157942Y49969D01*
X154741Y46768D01*
X143715D01*
G03X143264Y46483I0J-500D01*
G02X143265Y49657I-3344J1588D01*
G01X143327Y49527D01*
X143571Y49372D01*
X153663D01*
X156101Y51810D01*
X156139Y51918D01*
G02X156206Y52081I1420J-489D01*
G37*
G36*
G01X169982Y27727D02*
G02X170002Y27205I-6597J-514D01*
G02X156766I-6618J0D01*
G02X169982Y27727I6618J0D01*
G37*
G36*
G01X318745Y2000510D02*
X318604Y2000630D01*
X318544D01*
Y2000697D01*
X318444Y2000830D01*
G02X318044Y2002031I1601J1200D01*
G01Y2005215D01*
G02X321617Y2006454I2001J0D01*
G03X323202Y2006473I785J619D01*
G02X326804Y2005272I1601J-1201D01*
G01Y2002031D01*
G02X326404Y2000830I-2001J-1D01*
G01X326304Y2000697D01*
Y2000630D01*
X326244D01*
X326103Y2000510D01*
G02X323503I-1300J1521D01*
G01X323362Y2000630D01*
X323302D01*
Y2000697D01*
X323202Y2000830D01*
G02X322900Y2001412I1601J1200D01*
G03X321948I-476J-154D01*
G02X321646Y2000830I-1903J618D01*
G01X321546Y2000697D01*
Y2000630D01*
X321486D01*
X321345Y2000510D01*
G02X318745I-1300J1521D01*
G37*
G36*
G01X275299Y1896982D02*
G02X271816Y1898327I-1482J1345D01*
G01Y1901895D01*
G02X272216Y1903096I2001J1D01*
G01X272316Y1903229D01*
Y1903296D01*
X272376D01*
X272517Y1903416D01*
G02X275117I1300J-1521D01*
G01X275258Y1903296D01*
X275318D01*
Y1903229D01*
X275418Y1903096D01*
G02X275595Y1902814I-1601J-1201D01*
G03X276484I445J229D01*
G02X276661Y1903096I1778J-919D01*
G01X276760Y1903229D01*
Y1903296D01*
X276821D01*
X276962Y1903416D01*
G02X279562I1300J-1521D01*
G01X279703Y1903296D01*
X279764D01*
Y1903229D01*
X279863Y1903096D01*
G02X280044Y1902806I-1601J-1201D01*
G03X280935I446J227D01*
G02X281116Y1903096I1782J-911D01*
G01X281216Y1903229D01*
Y1903296D01*
X281276D01*
X281417Y1903416D01*
G02X284017I1300J-1521D01*
G01X284158Y1903296D01*
X284218D01*
Y1903229D01*
X284318Y1903096D01*
G02X284479Y1902845I-1600J-1203D01*
G03X285359I440J237D01*
G02X285520Y1903096I1761J-952D01*
G01X285620Y1903229D01*
Y1903296D01*
X285680D01*
X285821Y1903416D01*
G02X288421I1300J-1521D01*
G01X288562Y1903296D01*
X288622D01*
Y1903229D01*
X288722Y1903096D01*
G02X289122Y1901895I-1601J-1200D01*
G01Y1898327D01*
G02X285653Y1896967I-2001J0D01*
G03X284185I-734J-680D01*
G02X281232Y1896985I-1468J1360D01*
G03X279747I-743J-670D01*
G02X276780Y1896982I-1485J1342D01*
G03X275299I-741J-672D01*
G37*
G36*
G01X285323Y1825025D02*
X285182Y1825144D01*
X285122D01*
Y1825212D01*
X285022Y1825345D01*
G02X284622Y1826546I1601J1200D01*
G01Y1829400D01*
G02X288164Y1830678I2002J0D01*
G03X289805Y1830826I770J638D01*
G02X293552Y1829846I1745J-980D01*
G01Y1826546D01*
G02X293151Y1825345I-2002J1D01*
G01X293052Y1825212D01*
Y1825144D01*
X292991D01*
X292850Y1825025D01*
G02X290250I-1300J1521D01*
G01X290109Y1825144D01*
X290048D01*
Y1825212D01*
X289949Y1825345D01*
G02X289907Y1825403I1600J1203D01*
G03X288266I-821J-572D01*
G02X288224Y1825345I-1642J1145D01*
G01X288124Y1825212D01*
Y1825144D01*
X288064D01*
X287923Y1825025D01*
G02X285323I-1300J1521D01*
G37*
G36*
G01X82059Y1795080D02*
G02X78693I-1683J1083D01*
G03X77027Y1795104I-841J-541D01*
G02X73374Y1796236I-1651J1132D01*
G01Y1796261D01*
G03X72874Y1796761I-500J0D01*
G01X72674D01*
X72385Y1796485D01*
X72375Y1796285D01*
G02X68374Y1796383I-1999J98D01*
G01Y1801343D01*
G02X68695Y1802429I2002J-1D01*
G01X68774Y1802553D01*
Y1805244D01*
X71978D01*
Y1802553D01*
X72057Y1802429D01*
G02X72376Y1801412I-1681J-1086D01*
G03X73376I500J18D01*
G02X73695Y1802429I2000J-69D01*
G01X73774Y1802553D01*
Y1805244D01*
X76978D01*
Y1802553D01*
X77057Y1802429D01*
G02X77376Y1801412I-1681J-1086D01*
G03X78376I500J18D01*
G02X78695Y1802429I2000J-69D01*
G01X78774Y1802553D01*
Y1805244D01*
X81978D01*
Y1802553D01*
X82057Y1802429D01*
G02X82376Y1801412I-1681J-1086D01*
G03X83376I500J18D01*
G02X83695Y1802429I2000J-69D01*
G01X83774Y1802553D01*
Y1805244D01*
X86978D01*
Y1802553D01*
X87057Y1802429D01*
G02X87378Y1801343I-1681J-1087D01*
G01Y1796236D01*
G02X83725Y1795104I-2002J0D01*
G03X82059Y1795080I-825J-565D01*
G37*
G36*
G01X272702Y1723196D02*
Y1726915D01*
G02X273103Y1728116I2002J-1D01*
G01X273202Y1728249D01*
Y1728316D01*
X273263D01*
X273404Y1728436D01*
G02X276004I1300J-1521D01*
G01X276145Y1728316D01*
X276206D01*
Y1728249D01*
X276305Y1728116D01*
G02X276371Y1728023I-1599J-1204D01*
G03X278036I832J554D01*
G02X278102Y1728116I1665J-1111D01*
G01X278202Y1728249D01*
Y1728316D01*
X278262D01*
X278403Y1728436D01*
G02X281003I1300J-1521D01*
G01X281144Y1728316D01*
X281204D01*
Y1728249D01*
X281304Y1728116D01*
G02X281330Y1728081I-1594J-1211D01*
G03X282956I813J582D01*
G02X282982Y1728116I1620J-1176D01*
G01X283082Y1728249D01*
Y1728316D01*
X283142D01*
X283283Y1728436D01*
G02X285883I1300J-1521D01*
G01X286024Y1728316D01*
X286084D01*
Y1728249D01*
X286184Y1728116D01*
G02X286222Y1728064I-1597J-1207D01*
G03X287860I819J574D01*
G02X287898Y1728116I1635J-1155D01*
G01X287998Y1728249D01*
Y1728316D01*
X288058D01*
X288199Y1728436D01*
G02X290799I1300J-1521D01*
G01X290940Y1728316D01*
X291000D01*
Y1728249D01*
X291100Y1728116D01*
G02X291500Y1726915I-1601J-1200D01*
G01Y1723735D01*
G02X287923Y1722502I-2001J0D01*
G03X286285Y1722412I-788J-617D01*
G02X282972Y1722277I-1702J1053D01*
G03X281346Y1722255I-805J-593D01*
G02X277705Y1723285I-1643J1143D01*
G01Y1723286D01*
G03X277206Y1723757I-499J-29D01*
G01X276998D01*
X276706Y1723465D01*
Y1723196D01*
G02X272702I-2002J0D01*
G37*
G36*
G01X288121Y1650797D02*
X287980Y1650916D01*
X287920D01*
Y1650984D01*
X287820Y1651117D01*
G02X287420Y1652318I1601J1200D01*
G01Y1656558D01*
G02X290978Y1657816I2001J0D01*
G03X292533I777J629D01*
G02X296092Y1656558I1557J-1258D01*
G01Y1652318D01*
G02X295691Y1651117I-2002J1D01*
G01X295592Y1650984D01*
Y1650916D01*
X295531D01*
X295390Y1650797D01*
G02X292790I-1300J1521D01*
G01X292649Y1650916D01*
X292588D01*
Y1650984D01*
X292489Y1651117D01*
G02X292222Y1651599I1601J1202D01*
G03X291289I-467J-180D01*
G02X291022Y1651117I-1868J720D01*
G01X290922Y1650984D01*
Y1650916D01*
X290862D01*
X290721Y1650797D01*
G02X288121I-1300J1521D01*
G37*
G36*
G01X292595Y1541933D02*
G02X289052Y1543211I-1541J1278D01*
G01Y1547451D01*
G02X289453Y1548652I2002J-1D01*
G01X289552Y1548785D01*
Y1548852D01*
X289613D01*
X289754Y1548972D01*
G02X292354I1300J-1521D01*
G01X292495Y1548852D01*
X292556D01*
Y1548785D01*
X292655Y1548652D01*
G02X292903Y1548218I-1600J-1202D01*
G03X293826I461J192D01*
G02X294074Y1548652I1848J-768D01*
G01X294174Y1548785D01*
Y1548852D01*
X294234D01*
X294375Y1548972D01*
G02X296975I1300J-1521D01*
G01X297116Y1548852D01*
X297176D01*
Y1548785D01*
X297276Y1548652D01*
G02X297562Y1548118I-1601J-1201D01*
G03X298505I472J167D01*
G02X298791Y1548652I1887J-667D01*
G01X298890Y1548785D01*
Y1548852D01*
X298951D01*
X299092Y1548972D01*
G02X301692I1300J-1521D01*
G01X301833Y1548852D01*
X301894D01*
Y1548785D01*
X301993Y1548652D01*
G02X302183Y1548344I-1601J-1200D01*
G03X303079I448J223D01*
G02X303269Y1548652I1791J-892D01*
G01X303368Y1548785D01*
Y1548852D01*
X303429D01*
X303570Y1548972D01*
G02X306170I1300J-1521D01*
G01X306311Y1548852D01*
X306372D01*
Y1548785D01*
X306471Y1548652D01*
G02X306872Y1547451I-1601J-1202D01*
G01Y1543211D01*
G02X303377Y1541878I-2002J0D01*
G03X301885I-746J-666D01*
G02X298819Y1541973I-1493J1333D01*
G03X297248I-785J-618D01*
G02X294134Y1541933I-1573J1238D01*
G03X292595I-770J-638D01*
G37*
G36*
G01X274221Y1474116D02*
X274080Y1474236D01*
X274020D01*
Y1474303D01*
X273920Y1474436D01*
G02X273520Y1475637I1601J1200D01*
G01Y1479435D01*
G02X277011Y1480771I2001J0D01*
G03X278500I744J668D01*
G02X281992Y1479435I1490J-1336D01*
G01Y1475637D01*
G02X281591Y1474436I-2002J1D01*
G01X281492Y1474303D01*
Y1474236D01*
X281431D01*
X281290Y1474116D01*
G02X278690I-1300J1521D01*
G01X278549Y1474236D01*
X278488D01*
Y1474303D01*
X278389Y1474436D01*
G02X278202Y1474737I1600J1203D01*
G03X277309I-447J-225D01*
G02X277122Y1474436I-1787J902D01*
G01X277022Y1474303D01*
Y1474236D01*
X276962D01*
X276821Y1474116D01*
G02X274221I-1300J1521D01*
G37*
G36*
G01X281093Y1373307D02*
G02X277978Y1373265I-1574J1236D01*
G03X276490Y1373322I-770J-638D01*
G02X273587Y1373351I-1438J1393D01*
G03X272097Y1373321I-732J-682D01*
G02X268578Y1374626I-1518J1305D01*
G01Y1378341D01*
G02X268978Y1379542I2001J1D01*
G01X269078Y1379675D01*
Y1379742D01*
X269138D01*
X269279Y1379862D01*
G02X271879I1300J-1521D01*
G01X272020Y1379742D01*
X272080D01*
Y1379675D01*
X272180Y1379542D01*
G02X272368Y1379238I-1601J-1200D01*
G03X273263I448J224D01*
G02X273451Y1379542I1789J-896D01*
G01X273550Y1379675D01*
Y1379742D01*
X273611D01*
X273752Y1379862D01*
G02X276352I1300J-1521D01*
G01X276493Y1379742D01*
X276554D01*
Y1379675D01*
X276653Y1379542D01*
G02X276839Y1379243I-1600J-1203D01*
G03X277731I446J225D01*
G02X277917Y1379542I1786J-904D01*
G01X278016Y1379675D01*
Y1379742D01*
X278077D01*
X278218Y1379862D01*
G02X280818I1300J-1521D01*
G01X280959Y1379742D01*
X281020D01*
Y1379675D01*
X281119Y1379542D01*
G02X281407Y1379003I-1601J-1202D01*
G03X282351I472J165D01*
G02X282639Y1379543I1889J-661D01*
G01X282738Y1379676D01*
Y1379744D01*
X282799D01*
X282940Y1379863D01*
G02X285540I1300J-1521D01*
G01X285681Y1379744D01*
X285742D01*
Y1379676D01*
X285841Y1379543D01*
G02X286242Y1378342I-1601J-1202D01*
G01Y1374544D01*
G02X282666Y1373308I-2002J0D01*
G03X281093Y1373307I-786J-618D01*
G37*
G36*
G01X287910Y1300576D02*
X287769Y1300696D01*
X287708D01*
Y1300763D01*
X287609Y1300896D01*
G02X287208Y1302097I1601J1202D01*
G01Y1305634D01*
G02X290851Y1306779I2001J0D01*
G03X292492I821J573D01*
G02X296134Y1305634I1641J-1145D01*
G01Y1302097D01*
G02X295734Y1300896I-2001J-1D01*
G01X295634Y1300763D01*
Y1300696D01*
X295574D01*
X295433Y1300576D01*
G02X292833I-1300J1521D01*
G01X292692Y1300696D01*
X292632D01*
Y1300763D01*
X292532Y1300896D01*
G02X292492Y1300952I1608J1191D01*
G03X290851I-820J-573D01*
G02X290811Y1300896I-1648J1135D01*
G01X290712Y1300763D01*
Y1300696D01*
X290651D01*
X290510Y1300576D01*
G02X287910I-1300J1521D01*
G37*
G36*
G01X264104Y1190505D02*
G02X260558Y1191777I-1545J1272D01*
G01Y1195314D01*
G02X260958Y1196515I2001J1D01*
G01X261058Y1196648D01*
Y1196716D01*
X261118D01*
X261259Y1196835D01*
G02X263859I1300J-1521D01*
G01X264000Y1196716D01*
X264060D01*
Y1196648D01*
X264160Y1196515D01*
G02X264413Y1196067I-1602J-1200D01*
G03X265340I463J189D01*
G02X265593Y1196515I1855J-752D01*
G01X265692Y1196648D01*
Y1196716D01*
X265753D01*
X265894Y1196835D01*
G02X268494I1300J-1521D01*
G01X268635Y1196716D01*
X268696D01*
Y1196648D01*
X268795Y1196515D01*
G02X268824Y1196476I-1592J-1214D01*
G03X270452I814J580D01*
G02X270481Y1196515I1621J-1175D01*
G01X270580Y1196648D01*
Y1196716D01*
X270641D01*
X270782Y1196835D01*
G02X273382I1300J-1521D01*
G01X273523Y1196716D01*
X273584D01*
Y1196648D01*
X273683Y1196515D01*
G02X273972Y1195972I-1601J-1201D01*
G03X274917I473J164D01*
G02X275206Y1196515I1890J-658D01*
G01X275306Y1196648D01*
Y1196716D01*
X275366D01*
X275507Y1196835D01*
G02X278107I1300J-1521D01*
G01X278248Y1196716D01*
X278308D01*
Y1196648D01*
X278408Y1196515D01*
G02X278808Y1195314I-1601J-1200D01*
G01Y1191777D01*
G02X275232Y1190542I-2001J0D01*
G03X273657I-787J-616D01*
G02X270452Y1190615I-1575J1235D01*
G03X268824I-814J-580D01*
G02X265649Y1190505I-1630J1162D01*
G03X264104I-772J-635D01*
G37*
G36*
G01X286888Y1125905D02*
X286747Y1126024D01*
X286686D01*
Y1126092D01*
X286587Y1126225D01*
G02X286186Y1127426I1601J1202D01*
G01Y1131146D01*
G02X289692Y1132467I2002J0D01*
G03X291194I751J660D01*
G02X294700Y1131146I1504J-1321D01*
G01Y1127426D01*
G02X294299Y1126225I-2002J1D01*
G01X294200Y1126092D01*
Y1126024D01*
X294139D01*
X293998Y1125905D01*
G02X291398I-1300J1521D01*
G01X291257Y1126024D01*
X291196D01*
Y1126092D01*
X291097Y1126225D01*
G02X290894Y1126560I1602J1200D01*
G03X289992I-451J-217D01*
G02X289789Y1126225I-1805J865D01*
G01X289690Y1126092D01*
Y1126024D01*
X289629D01*
X289488Y1125905D01*
G02X286888I-1300J1521D01*
G37*
G36*
G01X282638Y1014853D02*
G02X279122Y1016162I-1514J1309D01*
G01Y1019882D01*
G02X279523Y1021083I2002J-1D01*
G01X279622Y1021216D01*
Y1021284D01*
X279683D01*
X279824Y1021403D01*
G02X282424I1300J-1521D01*
G01X282565Y1021284D01*
X282626D01*
Y1021216D01*
X282725Y1021083D01*
G02X282941Y1020721I-1601J-1201D01*
G03X283849I454J210D01*
G02X284065Y1021083I1817J-839D01*
G01X284164Y1021216D01*
Y1021284D01*
X284225D01*
X284366Y1021403D01*
G02X286966I1300J-1521D01*
G01X287107Y1021284D01*
X287168D01*
Y1021216D01*
X287267Y1021083D01*
G02X287443Y1020804I-1599J-1204D01*
G03X288330I443J230D01*
G02X288506Y1021083I1775J-925D01*
G01X288606Y1021216D01*
Y1021284D01*
X288666D01*
X288807Y1021403D01*
G02X291407I1300J-1521D01*
G01X291548Y1021284D01*
X291608D01*
Y1021216D01*
X291708Y1021083D01*
G02X291911Y1020748I-1602J-1200D01*
G03X292813I451J217D01*
G02X293016Y1021083I1805J-865D01*
G01X293116Y1021216D01*
Y1021284D01*
X293176D01*
X293317Y1021403D01*
G02X295917I1300J-1521D01*
G01X296058Y1021284D01*
X296118D01*
Y1021216D01*
X296218Y1021083D01*
G02X296618Y1019882I-1601J-1200D01*
G01Y1016162D01*
G02X293113Y1014841I-2001J0D01*
G03X291611I-751J-660D01*
G02X288626Y1014815I-1504J1321D01*
G03X287147I-740J-673D01*
G02X284152Y1014853I-1481J1347D01*
G03X282638I-757J-654D01*
G37*
G36*
G01X182918Y1013711D02*
X182785Y1013811D01*
X182144D01*
X182018Y1013728D01*
G02X180968Y1013412I-1050J1585D01*
G01X175668D01*
X174128Y1014951D01*
G02X176818Y1017641I1345J1345D01*
G01X177097Y1017361D01*
G03X177451Y1017214I354J353D01*
G01X180968D01*
G02X181065Y1017212I9J-1901D01*
G03X182116Y1018211I51J999D01*
G01Y1019280D01*
G02X183318Y1021115I2002J0D01*
G03X183626Y1022739I-399J917D01*
G01X183344Y1023020D01*
X182329D01*
G02X181129Y1023420I1J2002D01*
G01X180996Y1023520D01*
X180355D01*
X180229Y1023437D01*
G02X179179Y1023120I-1051J1585D01*
G01X177710D01*
X177242Y1022652D01*
G02X174552Y1025342I-1345J1345D01*
G01X176134Y1026924D01*
X179179D01*
G02X180229Y1026607I-1J-1902D01*
G01X180355Y1026524D01*
X180996D01*
X181129Y1026624D01*
G02X182329Y1027024I1201J-1602D01*
G01X185002D01*
X189800Y1022225D01*
G02X187541Y1018995I-1415J-1415D01*
G03X186120Y1018088I-421J-907D01*
G01Y1015313D01*
G02X185520Y1013885I-2002J1D01*
G01Y1013811D01*
X185451D01*
X185318Y1013711D01*
G02X182918I-1200J1602D01*
G37*
G36*
G01X289894Y950915D02*
X289753Y951034D01*
X289692D01*
Y951102D01*
X289593Y951235D01*
G02X289192Y952436I1601J1202D01*
G01Y956442D01*
G02X292754Y957695I2001J0D01*
G03X294314I780J627D01*
G02X297876Y956442I1561J-1253D01*
G01Y952436D01*
G02X297475Y951235I-2002J1D01*
G01X297376Y951102D01*
Y951034D01*
X297315D01*
X297174Y950915D01*
G02X294574I-1300J1521D01*
G01X294433Y951034D01*
X294372D01*
Y951102D01*
X294273Y951235D01*
G02X294002Y951728I1601J1201D01*
G03X293066I-468J-176D01*
G02X292795Y951235I-1872J708D01*
G01X292696Y951102D01*
Y951034D01*
X292635D01*
X292494Y950915D01*
G02X289894I-1300J1521D01*
G37*
G36*
G01X274800Y845906D02*
G02X271696Y846047I-1495J1331D01*
G03X270157Y846131I-804J-595D01*
G02X267223Y846122I-1471J1357D01*
G03X265722Y846077I-731J-683D01*
G02X262180Y847354I-1541J1277D01*
G01Y851243D01*
G02X262580Y852444I2001J1D01*
G01X262680Y852577D01*
Y852644D01*
X262740D01*
X262881Y852764D01*
G02X265481I1300J-1521D01*
G01X265622Y852644D01*
X265682D01*
Y852577D01*
X265782Y852444D01*
G02X265983Y852114I-1601J-1201D01*
G03X266884I450J217D01*
G02X267085Y852444I1802J-871D01*
G01X267184Y852577D01*
Y852644D01*
X267245D01*
X267386Y852764D01*
G02X269986I1300J-1521D01*
G01X270127Y852644D01*
X270188D01*
Y852577D01*
X270287Y852444D01*
G02X270534Y852012I-1601J-1202D01*
G03X271457I461J192D01*
G02X271704Y852444I1848J-770D01*
G01X271804Y852577D01*
Y852644D01*
X271864D01*
X272005Y852764D01*
G02X274605I1300J-1521D01*
G01X274746Y852644D01*
X274806D01*
Y852577D01*
X274906Y852444D01*
G02X275098Y852132I-1601J-1201D01*
G03X275995I448J221D01*
G02X276187Y852444I1793J-889D01*
G01X276286Y852577D01*
Y852644D01*
X276347D01*
X276488Y852764D01*
G02X279088I1300J-1521D01*
G01X279229Y852644D01*
X279290D01*
Y852577D01*
X279389Y852444D01*
G02X279790Y851243I-1601J-1202D01*
G01Y847237D01*
G02X276293Y845906I-2002J0D01*
G03X274800I-746J-665D01*
G37*
G36*
G01X276884Y777190D02*
X276743Y777310D01*
X276682D01*
Y777377D01*
X276583Y777510D01*
G02X276182Y778711I1601J1202D01*
G01Y782643D01*
G02X279702Y783947I2002J0D01*
G03X281219I759J652D01*
G02X284738Y782643I1518J-1304D01*
G01Y778711D01*
G02X284338Y777510I-2001J-1D01*
G01X284238Y777377D01*
Y777310D01*
X284178D01*
X284037Y777190D01*
G02X281437I-1300J1521D01*
G01X281296Y777310D01*
X281236D01*
Y777377D01*
X281136Y777510D01*
G02X280916Y777881I1601J1200D01*
G03X280005I-455J-207D01*
G02X279785Y777510I-1821J829D01*
G01X279686Y777377D01*
Y777310D01*
X279625D01*
X279484Y777190D01*
G02X276884I-1300J1521D01*
G37*
G36*
G01X271578Y670832D02*
G02X268108Y672192I-1468J1360D01*
G01Y676124D01*
G02X268508Y677325I2001J1D01*
G01X268608Y677458D01*
Y677526D01*
X268668D01*
X268809Y677645D01*
G02X271409I1300J-1521D01*
G01X271550Y677526D01*
X271610D01*
Y677458D01*
X271710Y677325D01*
G02X271871Y677073I-1601J-1201D01*
G03X272752I440J237D01*
G02X272913Y677325I1762J-949D01*
G01X273012Y677458D01*
Y677526D01*
X273073D01*
X273214Y677645D01*
G02X275814I1300J-1521D01*
G01X275955Y677526D01*
X276016D01*
Y677458D01*
X276115Y677325D01*
G02X276291Y677046I-1599J-1204D01*
G03X277178I443J230D01*
G02X277354Y677325I1775J-925D01*
G01X277454Y677458D01*
Y677526D01*
X277514D01*
X277655Y677645D01*
G02X280255I1300J-1521D01*
G01X280396Y677526D01*
X280456D01*
Y677458D01*
X280556Y677325D01*
G02X280709Y677088I-1601J-1201D01*
G03X281586I439J240D01*
G02X281739Y677325I1754J-964D01*
G01X281838Y677458D01*
Y677526D01*
X281899D01*
X282040Y677645D01*
G02X284640I1300J-1521D01*
G01X284781Y677526D01*
X284842D01*
Y677458D01*
X284941Y677325D01*
G02X285342Y676124I-1601J-1202D01*
G01Y672192D01*
G02X281878Y670825I-2002J0D01*
G03X280417I-731J-683D01*
G02X277474Y670845I-1462J1367D01*
G03X275995I-740J-673D01*
G02X273045Y670832I-1481J1347D01*
G03X271578I-733J-679D01*
G37*
G36*
G01X289684Y602116D02*
X289543Y602236D01*
X289482D01*
Y602303D01*
X289383Y602436D01*
G02X288982Y603637I1601J1202D01*
G01Y607215D01*
G02X292493Y608530I2002J0D01*
G03X294000I754J657D01*
G02X297510Y607215I1509J-1315D01*
G01Y603637D01*
G02X297110Y602436I-2001J-1D01*
G01X297010Y602303D01*
Y602236D01*
X296950D01*
X296809Y602116D01*
G02X294209I-1300J1521D01*
G01X294068Y602236D01*
X294008D01*
Y602303D01*
X293908Y602436D01*
G02X293699Y602783I1601J1201D01*
G03X292794I-452J-213D01*
G02X292585Y602436I-1810J854D01*
G01X292486Y602303D01*
Y602236D01*
X292425D01*
X292284Y602116D01*
G02X289684I-1300J1521D01*
G37*
G36*
G01X265990Y495987D02*
G02X262514Y497341I-1474J1354D01*
G01Y500919D01*
G02X262915Y502120I2002J-1D01*
G01X263014Y502253D01*
Y502320D01*
X263075D01*
X263216Y502440D01*
G02X265816I1300J-1521D01*
G01X265957Y502320D01*
X266018D01*
Y502253D01*
X266117Y502120D01*
G02X266285Y501855I-1601J-1201D01*
G03X267169I442J234D01*
G02X267337Y502120I1769J-936D01*
G01X267436Y502253D01*
Y502320D01*
X267497D01*
X267638Y502440D01*
G02X270238I1300J-1521D01*
G01X270379Y502320D01*
X270440D01*
Y502253D01*
X270539Y502120D01*
G02X270725Y501820I-1601J-1201D01*
G03X271618I447J225D01*
G02X271804Y502120I1787J-901D01*
G01X271904Y502253D01*
Y502320D01*
X271964D01*
X272105Y502440D01*
G02X274705I1300J-1521D01*
G01X274846Y502320D01*
X274906D01*
Y502253D01*
X275006Y502120D01*
G02X275154Y501893I-1599J-1204D01*
G03X276027I437J243D01*
G02X276175Y502120I1747J-977D01*
G01X276274Y502253D01*
Y502320D01*
X276335D01*
X276476Y502440D01*
G02X279076I1300J-1521D01*
G01X279217Y502320D01*
X279278D01*
Y502253D01*
X279377Y502120D01*
G02X279778Y500919I-1601J-1202D01*
G01Y497341D01*
G02X276319Y495969I-2002J0D01*
G03X274862I-728J-685D01*
G02X271916Y496004I-1457J1372D01*
G03X270427I-744J-668D01*
G02X267464Y495987I-1489J1337D01*
G03X265990I-737J-676D01*
G37*
G36*
G01X285365Y427494D02*
X285224Y427614D01*
X285164D01*
Y427681D01*
X285064Y427814D01*
G02X284664Y429015I1601J1200D01*
G01Y432844D01*
G02X288111Y434228I2001J0D01*
G03X289556I723J691D01*
G02X293004Y432844I1446J-1384D01*
G01Y429015D01*
G02X292603Y427814I-2002J1D01*
G01X292504Y427681D01*
Y427614D01*
X292443D01*
X292302Y427494D01*
G02X289702I-1300J1521D01*
G01X289561Y427614D01*
X289500D01*
Y427681D01*
X289401Y427814D01*
G02X289267Y428017I1600J1202D01*
G03X288400I-434J-249D01*
G02X288266Y427814I-1734J999D01*
G01X288166Y427681D01*
Y427614D01*
X288106D01*
X287965Y427494D01*
G02X285365I-1300J1521D01*
G37*
G36*
G01X116575Y414515D02*
X116513Y414645D01*
X116269Y414800D01*
X94318D01*
X92839Y416279D01*
X92731Y416317D01*
G02X92690Y419140I492J1419D01*
G03X93139Y420669I-355J935D01*
G02X94880Y420158I1208J893D01*
G03X94431Y418629I355J-935D01*
G02X94642Y418228I-1209J-892D01*
G01X94680Y418120D01*
X95396Y417404D01*
X108076D01*
G03X108783Y419111I0J1000D01*
G01X106342Y421552D01*
X106166D01*
Y421621D01*
X106090Y421804D01*
X105766Y422127D01*
Y422954D01*
G02X105774Y423125I1902J-3D01*
G03X104689Y424210I-996J89D01*
G02X104518Y424202I-174J1894D01*
G01X101990D01*
G02Y428006I0J1902D01*
G01X104518D01*
G02X104689Y427998I-3J-1902D01*
G03X105774Y429083I89J996D01*
G02X105766Y429254I1894J174D01*
G01Y433724D01*
X108130Y436088D01*
G02X110820Y433398I1345J-1345D01*
G01X109570Y432148D01*
Y429254D01*
G02X109567Y429157I-1902J10D01*
G03X110566Y428106I999J-51D01*
G01X113954D01*
X113956Y428104D01*
X116544D01*
G03X116946Y428306I0J500D01*
G02Y423898I2974J-2204D01*
G03X116544Y424100I-402J-298D01*
G01X115061D01*
X115046Y424086D01*
X112313D01*
X112296Y424102D01*
X111584D01*
G03X110877Y422395I0J-1000D01*
G01X112362Y420911D01*
G02X112759Y418804I-1345J-1344D01*
G03X113675Y417404I916J-400D01*
G01X116269D01*
X116513Y417559D01*
X116575Y417689D01*
G02Y414515I3345J-1587D01*
G37*
G36*
G01X282554Y321341D02*
G02X279072Y322688I-1480J1347D01*
G01Y326517D01*
G02X279473Y327718I2002J-1D01*
G01X279572Y327851D01*
Y327918D01*
X279633D01*
X279774Y328038D01*
G02X282374I1300J-1521D01*
G01X282515Y327918D01*
X282576D01*
Y327851D01*
X282675Y327718D01*
G02X282850Y327440I-1601J-1202D01*
G03X283737I443J231D01*
G02X283912Y327718I1776J-924D01*
G01X284012Y327851D01*
Y327918D01*
X284072D01*
X284213Y328038D01*
G02X286813I1300J-1521D01*
G01X286954Y327918D01*
X287014D01*
Y327851D01*
X287114Y327718D01*
G02X287266Y327483I-1600J-1202D01*
G03X288142I438J241D01*
G02X288294Y327718I1752J-967D01*
G01X288394Y327851D01*
Y327918D01*
X288454D01*
X288595Y328038D01*
G02X291195I1300J-1521D01*
G01X291336Y327918D01*
X291396D01*
Y327851D01*
X291496Y327718D01*
G02X291740Y327294I-1600J-1203D01*
G03X292661I460J194D01*
G02X292905Y327718I1844J-779D01*
G01X293004Y327851D01*
Y327918D01*
X293065D01*
X293206Y328038D01*
G02X295806I1300J-1521D01*
G01X295947Y327918D01*
X296008D01*
Y327851D01*
X296107Y327718D01*
G02X296508Y326517I-1601J-1202D01*
G01Y322688D01*
G02X292969Y321406I-2002J0D01*
G03X291432I-768J-640D01*
G02X288434Y321320I-1537J1282D01*
G03X286974I-730J-683D01*
G02X284033Y321341I-1461J1368D01*
G03X282554I-739J-674D01*
G37*
G36*
G01X275317Y251918D02*
X275176Y252038D01*
X275116D01*
Y252105D01*
X275016Y252238D01*
G02X274616Y253439I1601J1200D01*
G01Y256400D01*
G02X278079Y257766I2001J0D01*
G03X279604Y257841I731J683D01*
G02X283194Y256624I1589J-1217D01*
G01Y253439D01*
G02X282794Y252238I-2001J-1D01*
G01X282694Y252105D01*
Y252038D01*
X282634D01*
X282493Y251918D01*
G02X279893I-1300J1521D01*
G01X279752Y252038D01*
X279692D01*
Y252105D01*
X279592Y252238D01*
G02X279362Y252630I1600J1202D01*
G03X278448I-457J-202D01*
G02X278218Y252238I-1830J810D01*
G01X278118Y252105D01*
Y252038D01*
X278058D01*
X277917Y251918D01*
G02X275317I-1300J1521D01*
G37*
G36*
G01X268954Y146255D02*
G02X265932Y146202I-1534J1285D01*
G03X264488Y146247I-744J-669D01*
G02X261084Y147675I-1402J1428D01*
G01Y151264D01*
G02X261485Y152465I2002J-1D01*
G01X261584Y152598D01*
Y152666D01*
X261645D01*
X261786Y152785D01*
G02X264386I1300J-1521D01*
G01X264527Y152666D01*
X264588D01*
Y152598D01*
X264687Y152465D01*
G02X264820Y152264I-1600J-1203D01*
G03X265686I433J250D01*
G02X265819Y152465I1733J-1002D01*
G01X265918Y152598D01*
Y152666D01*
X265979D01*
X266120Y152785D01*
G02X268720I1300J-1521D01*
G01X268861Y152666D01*
X268922D01*
Y152598D01*
X269021Y152465D01*
G02X269229Y152119I-1602J-1199D01*
G03X270134I453J214D01*
G02X270342Y152465I1810J-853D01*
G01X270442Y152598D01*
Y152666D01*
X270502D01*
X270643Y152785D01*
G02X273243I1300J-1521D01*
G01X273384Y152666D01*
X273444D01*
Y152598D01*
X273544Y152465D01*
G02X273775Y152069I-1602J-1200D01*
G03X274691I458J202D01*
G02X274922Y152465I1833J-804D01*
G01X275022Y152598D01*
Y152666D01*
X275082D01*
X275223Y152785D01*
G02X277823I1300J-1521D01*
G01X277964Y152666D01*
X278024D01*
Y152598D01*
X278124Y152465D01*
G02X278524Y151264I-1601J-1200D01*
G01Y147585D01*
G02X274983Y146306I-2001J0D01*
G03X273457Y146321I-769J-639D01*
G02X270461Y146285I-1514J1309D01*
G03X268954Y146255I-740J-672D01*
G37*
G36*
G01X298387Y73872D02*
X298246Y73992D01*
X298186D01*
Y74059D01*
X298086Y74192D01*
G02X297686Y75393I1601J1200D01*
G01Y78778D01*
G02X301175Y80116I2001J0D01*
G03X302663I744J669D01*
G02X305651Y80103I1488J-1338D01*
G03X307151I750J662D01*
G02X310131Y80126I1500J-1325D01*
G03X311609I739J673D01*
G02X314582Y80111I1480J-1348D01*
G03X316074I746J666D01*
G02X319047Y80126I1493J-1333D01*
G03X320525I739J673D01*
G02X324006Y78778I1479J-1348D01*
G01Y75393D01*
G02X323606Y74192I-2001J-1D01*
G01X323506Y74059D01*
Y73992D01*
X323446D01*
X323305Y73872D01*
G02X320705I-1300J1521D01*
G01X320564Y73992D01*
X320504D01*
Y74059D01*
X320404Y74192D01*
G02X320230Y74469I1602J1199D01*
G03X319342I-444J-231D01*
G02X319168Y74192I-1776J922D01*
G01X319068Y74059D01*
Y73992D01*
X319008D01*
X318867Y73872D01*
G02X316267I-1300J1521D01*
G01X316126Y73992D01*
X316066D01*
Y74059D01*
X315966Y74192D01*
G02X315776Y74500I1601J1200D01*
G03X314880I-448J-223D01*
G02X314690Y74192I-1791J892D01*
G01X314590Y74059D01*
Y73992D01*
X314530D01*
X314389Y73872D01*
G02X311789I-1300J1521D01*
G01X311648Y73992D01*
X311588D01*
Y74059D01*
X311488Y74192D01*
G02X311314Y74469I1602J1199D01*
G03X310426I-444J-231D01*
G02X310252Y74192I-1776J922D01*
G01X310152Y74059D01*
Y73992D01*
X310092D01*
X309951Y73872D01*
G02X307351I-1300J1521D01*
G01X307210Y73992D01*
X307150D01*
Y74059D01*
X307050Y74192D01*
G02X306851Y74518I1601J1201D01*
G03X305951I-450J-218D01*
G02X305752Y74192I-1800J875D01*
G01X305652Y74059D01*
Y73992D01*
X305592D01*
X305451Y73872D01*
G02X302851I-1300J1521D01*
G01X302710Y73992D01*
X302650D01*
Y74059D01*
X302550Y74192D01*
G02X302365Y74489I1600J1203D01*
G03X301473I-446J-225D01*
G02X301288Y74192I-1785J906D01*
G01X301188Y74059D01*
Y73992D01*
X301128D01*
X300987Y73872D01*
G02X298387I-1300J1521D01*
G37*
G54D61*
X61888Y666012D03*
X57124Y675327D03*
X54483Y679810D03*
X59236Y670758D03*
X102960Y672823D03*
X144878Y1738861D03*
X158618Y1399448D03*
X164037Y1400226D03*
X170351Y1401324D03*
X163257Y1737619D03*
X150309Y1737009D03*
X168151Y1739208D03*
X165782Y1732903D03*
X156183Y1735240D03*
X176083Y1402321D03*
X173394Y1736051D03*
X308057Y248863D03*
X306267Y241010D03*
X314914Y238162D03*
X314940Y252083D03*
X309678Y1053262D03*
X314183Y1403423D03*
X312077Y1575871D03*
X331403Y51409D03*
X333889Y56021D03*
X338227Y61559D03*
X320372Y225979D03*
X318088Y231820D03*
X321899Y238137D03*
X331046Y232021D03*
X320961Y250105D03*
X324709Y231580D03*
X335522Y404033D03*
X323313Y418313D03*
X326196Y413982D03*
X328950Y409216D03*
X320980Y423225D03*
X336617Y577978D03*
X319305Y582111D03*
X329636Y584715D03*
X317724Y588250D03*
X337387Y586230D03*
X320380Y576491D03*
X331867Y589810D03*
X333750Y595326D03*
X321742Y599041D03*
X331568Y752967D03*
X339012Y752859D03*
X329336Y762693D03*
X334010Y758588D03*
X327524Y758020D03*
X329938Y948756D03*
X332527Y943746D03*
X324098Y946104D03*
X318557Y941178D03*
X323868Y929978D03*
X326646Y939788D03*
X336160Y937262D03*
X328583Y933262D03*
X321425Y951577D03*
X324246Y1051786D03*
X335677Y1048904D03*
X317592Y1053050D03*
X337509Y1109598D03*
X328989Y1121090D03*
X326558Y1126368D03*
X327452Y1279447D03*
X321978Y1282086D03*
X329619Y1284016D03*
X327932Y1289221D03*
X325636Y1399114D03*
X334646Y1400804D03*
X323720Y1570924D03*
X333474Y1566686D03*
X335963Y1573797D03*
X323813Y1753231D03*
X329887Y1752081D03*
X332399Y1926787D03*
X359931Y52189D03*
X348289Y50863D03*
X345089Y56190D03*
X340373Y51579D03*
X361799Y311938D03*
X362236Y324983D03*
X342097Y401684D03*
X363825Y401768D03*
X342900Y580126D03*
X354000Y652170D03*
X356559Y675167D03*
X362577Y752783D03*
X344109Y751809D03*
X343656Y933725D03*
X345578Y1047844D03*
X344099Y1106798D03*
X344130Y1401670D03*
X350690Y1403243D03*
X348710Y1570187D03*
X361011Y1568890D03*
X343402Y1572080D03*
X348245Y1575241D03*
X355364Y1570990D03*
X352337Y1887285D03*
X345537Y1916558D03*
X344402Y1911123D03*
X363361Y1918313D03*
X358318Y1920680D03*
X363411Y1923459D03*
X340336Y1922409D03*
X372204Y56126D03*
X379257Y52158D03*
X387524Y76847D03*
X374442Y406857D03*
X374542Y401282D03*
X368907Y404308D03*
X376654Y754748D03*
X382892Y767710D03*
X386790Y774338D03*
X379335Y1189778D03*
X383276Y1184136D03*
X386816Y1179841D03*
X376472Y1194999D03*
X373674Y1199967D03*
X371523Y1204725D03*
X373564Y1352548D03*
X374681Y1365620D03*
X367829Y1566108D03*
X366306Y1899864D03*
X374431Y1901397D03*
X374775Y1919243D03*
X379403Y1917261D03*
X369748Y1921795D03*
G54D62*
X15547Y723112D03*
Y730986D03*
X25389Y723112D03*
Y730986D03*
X15547Y738860D03*
Y746734D03*
Y754608D03*
X25389Y738860D03*
Y746734D03*
Y754608D03*
X15547Y762483D03*
Y770357D03*
Y778231D03*
X25389Y762483D03*
Y770357D03*
Y778231D03*
X15547Y786105D03*
Y793979D03*
X25389Y786105D03*
Y793979D03*
X33263Y727049D03*
Y734923D03*
Y742797D03*
Y750671D03*
Y758545D03*
Y766419D03*
Y774293D03*
Y782167D03*
Y790041D03*
G54D54*
X14073Y522000D03*
X65254Y519500D03*
Y529500D03*
Y539500D03*
X55254Y524500D03*
Y534500D03*
X65254Y549500D03*
X55254Y544500D03*
X14073Y1580004D03*
X65254Y1577504D03*
Y1587504D03*
Y1597504D03*
X55254Y1582504D03*
Y1592504D03*
Y1602504D03*
X65254Y1607504D03*
G54D52*
X22756Y113818D03*
X22480Y316838D03*
X22756Y1866819D03*
Y1948818D03*
Y2023818D03*
G54D74*
X173385Y21890D03*
X183385Y32520D03*
Y21890D03*
X193385Y32520D03*
Y21890D03*
X173385Y196890D03*
X183385D03*
X193385D03*
X183385Y207520D03*
X193385D03*
X173385Y371890D03*
X183385D03*
X193385D03*
X183385Y382520D03*
X193385D03*
X173386Y546890D03*
X183386Y557520D03*
Y546890D03*
X193386Y557520D03*
Y546890D03*
X173386Y721890D03*
X183386Y732520D03*
Y721890D03*
X193386Y732520D03*
Y721890D03*
X173385Y896890D03*
X183385D03*
X193385D03*
X183385Y907520D03*
X193385D03*
X173385Y1071890D03*
X183385D03*
X193385D03*
X183385Y1082520D03*
X193385D03*
X173385Y1246890D03*
X183385Y1257520D03*
Y1246890D03*
X193385Y1257520D03*
Y1246890D03*
X173385Y1421890D03*
X183385Y1432520D03*
Y1421890D03*
X193385Y1432520D03*
Y1421890D03*
X173385Y1596890D03*
X183385D03*
X193385D03*
X183385Y1607520D03*
X193385D03*
X173385Y1771890D03*
X183385D03*
X193385D03*
X183385Y1782520D03*
X193385D03*
X173385Y1946890D03*
X183385Y1957520D03*
Y1946890D03*
X193385Y1957520D03*
Y1946890D03*
X203385Y32520D03*
Y21890D03*
X213385Y32520D03*
Y21890D03*
X203385Y196890D03*
X213385D03*
X203385Y207520D03*
X213385D03*
X203385Y371890D03*
X213385D03*
X203385Y382520D03*
X213385D03*
X203386Y557520D03*
Y546890D03*
X213386Y557520D03*
Y546890D03*
X203386Y732520D03*
Y721890D03*
X213386Y732520D03*
Y721890D03*
X203385Y896890D03*
X213385D03*
X203385Y907520D03*
X213385D03*
X203385Y1071890D03*
X213385D03*
X203385Y1082520D03*
X213385D03*
X203385Y1257520D03*
Y1246890D03*
X213385Y1257520D03*
Y1246890D03*
X203385Y1432520D03*
Y1421890D03*
X213385Y1432520D03*
Y1421890D03*
X203385Y1596890D03*
X213385D03*
X203385Y1607520D03*
X213385D03*
X203385Y1771890D03*
X213385D03*
X203385Y1782520D03*
X213385D03*
X203385Y1957520D03*
Y1946890D03*
X213385Y1957520D03*
Y1946890D03*
X223385Y32520D03*
Y21890D03*
X233385Y32520D03*
Y21890D03*
X243385Y32520D03*
Y21890D03*
X223385Y196890D03*
X233385D03*
X243385D03*
X223385Y207520D03*
X233385D03*
X243385D03*
X223385Y371890D03*
X233385D03*
X243385D03*
X223385Y382520D03*
X233385D03*
X243385D03*
X223386Y557520D03*
Y546890D03*
X233386Y557520D03*
Y546890D03*
X243386Y557520D03*
Y546890D03*
X223386Y732520D03*
Y721890D03*
X233386Y732520D03*
Y721890D03*
X243386Y732520D03*
Y721890D03*
X223385Y896890D03*
X233385D03*
X243385D03*
X223385Y907520D03*
X233385D03*
X243385D03*
X223385Y1071890D03*
X233385D03*
X243385D03*
X223385Y1082520D03*
X233385D03*
X243385D03*
X223385Y1257520D03*
Y1246890D03*
X233385Y1257520D03*
Y1246890D03*
X243385Y1257520D03*
Y1246890D03*
X223385Y1432520D03*
Y1421890D03*
X233385Y1432520D03*
Y1421890D03*
X243385Y1432520D03*
Y1421890D03*
X223385Y1596890D03*
X233385D03*
X243385D03*
X223385Y1607520D03*
X233385D03*
X243385D03*
X223385Y1771890D03*
X233385D03*
X243385D03*
X223385Y1782520D03*
X233385D03*
X243385D03*
X223385Y1957520D03*
Y1946890D03*
X233385Y1957520D03*
Y1946890D03*
X243385Y1957520D03*
Y1946890D03*
X337165Y24705D03*
Y34705D03*
Y199705D03*
Y209705D03*
Y374705D03*
Y384705D03*
X337166Y549705D03*
Y559705D03*
Y724705D03*
Y734705D03*
X337165Y899705D03*
Y909705D03*
Y1074705D03*
Y1084705D03*
Y1249705D03*
Y1259705D03*
Y1424705D03*
Y1434705D03*
Y1599705D03*
Y1609705D03*
Y1774705D03*
Y1784705D03*
Y1949705D03*
Y1959705D03*
X342165Y19705D03*
Y29705D03*
X347165Y24705D03*
X352165Y19705D03*
Y29705D03*
X357165Y24705D03*
X362165Y19705D03*
Y29705D03*
X347165Y34705D03*
X357165D03*
X342165Y194705D03*
X347165Y199705D03*
X352165Y194705D03*
X357165Y199705D03*
X362165Y194705D03*
X342165Y204705D03*
X347165Y209705D03*
X352165Y204705D03*
X357165Y209705D03*
X362165Y204705D03*
X342165Y369705D03*
X352165D03*
X362165D03*
X342165Y379705D03*
X347165Y374705D03*
Y384705D03*
X352165Y379705D03*
X357165Y374705D03*
Y384705D03*
X362165Y379705D03*
X342166Y544705D03*
Y554705D03*
X347166Y549705D03*
Y559705D03*
X352166Y544705D03*
Y554705D03*
X357166Y549705D03*
Y559705D03*
X362166Y544705D03*
Y554705D03*
X342166Y719705D03*
Y729705D03*
X347166Y724705D03*
X352166Y719705D03*
Y729705D03*
X357166Y724705D03*
X362166Y719705D03*
Y729705D03*
X347166Y734705D03*
X357166D03*
X342165Y894705D03*
X347165Y899705D03*
X352165Y894705D03*
X357165Y899705D03*
X362165Y894705D03*
X342165Y904705D03*
X347165Y909705D03*
X352165Y904705D03*
X357165Y909705D03*
X362165Y904705D03*
X342165Y1069705D03*
X352165D03*
X362165D03*
X342165Y1079705D03*
X347165Y1074705D03*
Y1084705D03*
X352165Y1079705D03*
X357165Y1074705D03*
Y1084705D03*
X362165Y1079705D03*
X342165Y1244705D03*
Y1254705D03*
X347165Y1249705D03*
Y1259705D03*
X352165Y1244705D03*
Y1254705D03*
X357165Y1249705D03*
Y1259705D03*
X362165Y1244705D03*
Y1254705D03*
X342165Y1419705D03*
Y1429705D03*
X347165Y1424705D03*
Y1434705D03*
X352165Y1419705D03*
Y1429705D03*
X357165Y1424705D03*
Y1434705D03*
X362165Y1419705D03*
Y1429705D03*
X342165Y1594705D03*
X347165Y1599705D03*
X352165Y1594705D03*
X357165Y1599705D03*
X362165Y1594705D03*
X342165Y1604705D03*
X347165Y1609705D03*
X352165Y1604705D03*
X357165Y1609705D03*
X362165Y1604705D03*
X342165Y1769705D03*
X352165D03*
X362165D03*
X342165Y1779705D03*
X347165Y1774705D03*
Y1784705D03*
X352165Y1779705D03*
X357165Y1774705D03*
Y1784705D03*
X362165Y1779705D03*
X342165Y1944705D03*
Y1954705D03*
X347165Y1949705D03*
Y1959705D03*
X352165Y1944705D03*
Y1954705D03*
X357165Y1949705D03*
Y1959705D03*
X362165Y1944705D03*
Y1954705D03*
G54D73*
X119920Y18071D03*
Y98071D03*
Y108071D03*
Y118071D03*
Y128071D03*
Y138071D03*
Y148071D03*
Y158071D03*
Y168071D03*
Y178071D03*
Y188071D03*
Y198071D03*
Y208071D03*
Y366102D03*
Y436102D03*
Y446102D03*
Y456102D03*
Y466102D03*
Y476102D03*
Y486102D03*
Y496102D03*
Y506102D03*
Y516102D03*
Y526102D03*
Y536102D03*
Y546102D03*
Y556102D03*
Y854134D03*
Y864134D03*
Y874134D03*
Y884134D03*
Y894134D03*
Y904134D03*
Y1232165D03*
Y1242165D03*
Y1252165D03*
Y1828228D03*
Y1838228D03*
Y1848228D03*
Y1858228D03*
Y1868228D03*
Y1878228D03*
Y1888228D03*
Y1898228D03*
Y1908228D03*
Y1918228D03*
Y1928228D03*
Y1938228D03*
Y1948228D03*
X139920Y28071D03*
Y18071D03*
Y58071D03*
Y38071D03*
Y98071D03*
Y128071D03*
Y118071D03*
Y108071D03*
Y148071D03*
Y138071D03*
Y178071D03*
Y168071D03*
Y158071D03*
Y198071D03*
Y188071D03*
Y208071D03*
Y366102D03*
Y386102D03*
Y376102D03*
Y406102D03*
Y466102D03*
Y456102D03*
Y446102D03*
Y486102D03*
Y476102D03*
Y516102D03*
Y506102D03*
Y496102D03*
Y536102D03*
Y526102D03*
Y556102D03*
Y546102D03*
Y804134D03*
Y824134D03*
Y814134D03*
Y854134D03*
Y844134D03*
Y834134D03*
Y874134D03*
Y864134D03*
Y904134D03*
Y894134D03*
Y884134D03*
Y1142165D03*
Y1162165D03*
Y1152165D03*
Y1192165D03*
Y1182165D03*
Y1172165D03*
Y1212165D03*
Y1202165D03*
Y1242165D03*
Y1232165D03*
Y1222165D03*
Y1252165D03*
Y1410197D03*
Y1430197D03*
Y1420197D03*
Y1500197D03*
Y1530197D03*
Y1520197D03*
Y1510197D03*
Y1550197D03*
Y1540197D03*
Y1580197D03*
Y1570197D03*
Y1560197D03*
Y1600197D03*
Y1590197D03*
Y1768228D03*
Y1758228D03*
Y1798228D03*
Y1778228D03*
Y1838228D03*
Y1868228D03*
Y1858228D03*
Y1848228D03*
Y1888228D03*
Y1878228D03*
Y1918228D03*
Y1908228D03*
Y1898228D03*
Y1938228D03*
Y1928228D03*
Y1948228D03*
G54D57*
X64979Y35500D03*
Y45500D03*
Y55500D03*
X54979Y40500D03*
Y50500D03*
X64979Y65500D03*
X54979Y60500D03*
X64979Y171500D03*
X54979Y176500D03*
X64979Y181500D03*
Y191500D03*
Y201500D03*
X54979Y186500D03*
Y196500D03*
X64979Y244500D03*
X54979Y249500D03*
X64979Y254500D03*
Y264500D03*
Y274500D03*
X54979Y259500D03*
Y269500D03*
X64979Y380500D03*
Y390500D03*
X54979Y385500D03*
Y395500D03*
X64979Y400500D03*
Y410500D03*
X54979Y405500D03*
X189762Y73105D03*
X190289Y152050D03*
X190357Y247568D03*
X190817Y331786D03*
X189761Y421732D03*
X190553Y506517D03*
X192888Y598130D03*
X190816Y681645D03*
X191846Y774526D03*
X191606Y856244D03*
X196311Y947202D03*
X195516Y1032544D03*
X191250Y1122856D03*
X191342Y1206233D03*
X191846Y1299104D03*
X190552Y1380966D03*
X189463Y1474162D03*
X191079Y1557277D03*
X192143Y1648177D03*
X191607Y1731351D03*
X191530Y1823227D03*
X190289Y1900420D03*
X192125Y1998730D03*
X191530Y2043388D03*
G54D71*
X23402Y1668874D03*
Y1685410D03*
Y1701945D03*
Y1718480D03*
Y1735016D03*
Y1751551D03*
Y1768087D03*
Y1784622D03*
Y1817693D03*
Y1801158D03*
X45056Y1668874D03*
Y1718480D03*
Y1768087D03*
G54D51*
X30473Y102007D03*
Y137440D03*
X30197Y305027D03*
Y352271D03*
G54D67*
X30473Y1890441D03*
Y1937007D03*
Y1972440D03*
Y2012007D03*
Y2047440D03*
G54D56*
X45411Y505996D03*
Y568004D03*
Y1564000D03*
Y1626008D03*
G54D55*
X20468Y696341D03*
G54D48*
X65354Y114960D03*
Y464960D03*
X307086Y127165D03*
Y477165D03*
Y827165D03*
Y1343504D03*
X65354Y1514960D03*
X307086Y1693504D03*
X307087Y2043503D03*
G54D59*
X55254Y554500D03*
Y1612504D03*
G54D70*
X388591Y62106D03*
X385616Y1991570D03*
G54D49*
X29979Y30500D03*
Y75500D03*
Y166500D03*
Y211500D03*
Y239500D03*
Y284500D03*
Y375500D03*
Y420500D03*
G54D78*
X65354Y814960D03*
Y1164960D03*
G54D76*
X204333Y506517D03*
X204859Y1557277D03*
X205923Y1648177D03*
X205387Y1731351D03*
G54D69*
X373385Y32520D03*
Y207520D03*
Y382520D03*
X373386Y557520D03*
Y732520D03*
X373385Y907520D03*
Y1082520D03*
Y1257520D03*
Y1432520D03*
Y1607520D03*
Y1782520D03*
Y1957520D03*
G54D75*
X203542Y73105D03*
X204596Y681645D03*
X205122Y1206233D03*
X205310Y1823227D03*
G54D66*
X307086Y308268D03*
G54D63*
X173385Y1957520D03*
Y1782520D03*
Y1607520D03*
Y1432520D03*
Y1257520D03*
Y1082520D03*
Y907520D03*
Y382520D03*
Y207520D03*
Y32520D03*
G54D60*
X72180Y675710D03*
X92980D03*
G54D58*
X54979Y70500D03*
Y206500D03*
Y279500D03*
Y415500D03*
X204069Y152050D03*
X204137Y247568D03*
X204597Y331786D03*
X203541Y421732D03*
X210091Y947202D03*
X203243Y1474162D03*
X204069Y1900420D03*
X205905Y1998730D03*
G54D53*
X22480Y340460D03*
G54D50*
X30254Y514500D03*
Y559500D03*
Y1572504D03*
Y1617504D03*
G54D77*
X206668Y598130D03*
X205626Y774526D03*
X205386Y856244D03*
X209296Y1032544D03*
X205030Y1122856D03*
X205626Y1299104D03*
X204332Y1380966D03*
X205310Y2043388D03*
G54D64*
X173386Y732520D03*
Y557520D03*
G54D72*
X45056Y1817693D03*
G54D65*
X307086Y1883071D03*
G54D68*
X359842Y78780D03*
Y253780D03*
Y428780D03*
Y603780D03*
Y778780D03*
Y953780D03*
Y1128780D03*
Y1303780D03*
Y1478780D03*
Y1653780D03*
Y1828780D03*
Y2003780D03*
%LPD*%
G75*
G36*
G01X65354Y95260D02*
G02I0J19700D01*
G37*
G36*
G01Y445260D02*
G02I0J19700D01*
G37*
G36*
G01Y1495260D02*
G02I0J19700D01*
G37*
G36*
G01Y1845260D02*
G02I0J19700D01*
G37*
G36*
G01X326786Y127165D02*
G02I-19700J0D01*
G37*
G36*
G01Y477165D02*
G02I-19700J0D01*
G37*
G36*
G01Y827165D02*
G02I-19700J0D01*
G37*
G36*
G01Y1343504D02*
G02I-19700J0D01*
G37*
G36*
G01Y1693504D02*
G02I-19700J0D01*
G37*
G36*
G01X326787Y2043503D02*
G02I-19700J0D01*
G37*
%LPC*%
G75*
G54D78*
X65354Y114960D03*
Y464960D03*
Y1514960D03*
Y1864960D03*
X307086Y127165D03*
Y477165D03*
Y827165D03*
Y1343504D03*
Y1693504D03*
X307087Y2043503D03*
%LPD*%
G75*
G54D10*
X29979Y30500D03*
Y75500D03*
Y166500D03*
Y211500D03*
Y239500D03*
Y284500D03*
Y375500D03*
Y420500D03*
G54D20*
X14691Y1559284D03*
X11541D03*
X54014Y904196D03*
X50864D03*
X54413Y1253378D03*
X51263D03*
X54210Y1263103D03*
X51060D03*
X54277Y1257633D03*
X51127D03*
X54582Y1279783D03*
X51432D03*
X54548Y1267290D03*
X51398D03*
X54446Y1284038D03*
X51296D03*
X54582Y1275630D03*
X51432D03*
X54481Y1271544D03*
X51331D03*
X59609Y1778371D03*
X62759D03*
X62637Y1782985D03*
X59487D03*
X86266Y1771103D03*
X83116D03*
X105845Y20080D03*
X108995D03*
X100778Y28320D03*
X103928D03*
X100693Y24203D03*
X103843D03*
X105845Y15847D03*
X108995D03*
X108090Y46285D03*
X104940D03*
X104932Y41803D03*
X108082D03*
X100778Y32853D03*
X103928D03*
X100778Y37438D03*
X103928D03*
X104137Y78186D03*
X107287D03*
X102727Y58250D03*
X105877D03*
X100518Y391220D03*
X103668D03*
X100518Y376580D03*
X103668D03*
X100518Y386235D03*
X103668D03*
X100518Y381386D03*
X103668D03*
X100518Y371909D03*
X103668D03*
X100518Y396024D03*
X103668D03*
X100794Y400352D03*
X103944D03*
X104518Y426104D03*
X107668D03*
X101056Y720745D03*
X104206D03*
X101056Y730398D03*
X104206D03*
X101056Y725457D03*
X104206D03*
X101056Y715937D03*
X104206D03*
X104346Y745139D03*
X101196D03*
X101056Y735248D03*
X104206D03*
X101056Y739962D03*
X104206D03*
X101520Y749481D03*
X104670D03*
X104442Y774100D03*
X107592D03*
X101189Y1067515D03*
X104339D03*
X101189Y1092036D03*
X104339D03*
X101189Y1072226D03*
X104339D03*
X101189Y1081791D03*
X104339D03*
X101189Y1076901D03*
X104339D03*
X101189Y1087095D03*
X104339D03*
X104432Y1096403D03*
X101282D03*
X105880Y1102535D03*
X109030D03*
X105684Y1122166D03*
X108834D03*
X100227Y1419492D03*
X103377D03*
X100227Y1429195D03*
X103377D03*
X100227Y1424340D03*
X103377D03*
X103443Y1447919D03*
X100293D03*
X100227Y1443743D03*
X103377D03*
X100227Y1434041D03*
X103377D03*
X100227Y1438980D03*
X103377D03*
X100019Y1453131D03*
X103169D03*
X105390Y1470205D03*
X108540D03*
X101677Y1760827D03*
X104827D03*
X101677Y1770527D03*
X104827D03*
X101677Y1765722D03*
X104827D03*
X104930Y1789947D03*
X101780D03*
X101677Y1785571D03*
X104827D03*
X101677Y1775514D03*
X104827D03*
X101677Y1780542D03*
X104827D03*
X105669Y1818228D03*
X108819D03*
X103671Y1798224D03*
X106821D03*
X159676Y56744D03*
X156526D03*
X158463Y68130D03*
X155313D03*
X155202Y72497D03*
X158352D03*
X158559Y88108D03*
X155409D03*
X158490Y407575D03*
X155340D03*
X158498Y436119D03*
X155348D03*
X158950Y756757D03*
X155800D03*
X158665Y764231D03*
X155515D03*
X155113Y776673D03*
X158263D03*
X158519Y784141D03*
X155369D03*
X159278Y1106853D03*
X156128D03*
X158497Y1132178D03*
X155347D03*
X160252Y1457084D03*
X157102D03*
X158976Y1480269D03*
X155826D03*
X159505Y1462651D03*
X156355D03*
X155648Y1473020D03*
X158798D03*
X158840Y1807740D03*
X155690D03*
X158563Y1815631D03*
X155413D03*
X158806Y1828225D03*
X155656D03*
X155409Y1820360D03*
X158559D03*
X184373Y937979D03*
X181223D03*
X184284Y943579D03*
X181134D03*
X184196Y962671D03*
X181046D03*
X184285Y957071D03*
X181135D03*
X184539Y973554D03*
X181389D03*
X184397Y990958D03*
X181247D03*
X184632Y979154D03*
X181482D03*
X184353Y996558D03*
X181203D03*
X184118Y1015313D03*
X180968D03*
X184115Y1009713D03*
X180965D03*
X182329Y1025022D03*
X179179D03*
X182327Y1030622D03*
X179177D03*
X264685Y128228D03*
X261535D03*
X264929Y115559D03*
X261779D03*
X264175Y823604D03*
X261025D03*
X264335Y812170D03*
X261185D03*
X272111Y463099D03*
X268961D03*
X272038Y473677D03*
X268888D03*
X288712Y1864565D03*
X285562D03*
X288794Y1858668D03*
X285644D03*
X308906Y1524401D03*
X305756D03*
X308636Y1513883D03*
X305486D03*
X320208Y1162266D03*
X317058D03*
X320264Y1172804D03*
X317114D03*
G54D11*
G01X13441Y498765D02*
Y495961D01*
G01X10914Y576211D02*
Y578848D01*
G01X15984Y576277D02*
Y578849D01*
G01X46980Y1335843D02*
X42480D01*
X40151Y1333514D01*
X32250D01*
X28229Y1329493D01*
X12984D01*
X7677Y1334800D01*
Y1337283D01*
G01X11541Y1559284D02*
Y1562330D01*
G01X11153Y1635435D02*
Y1638435D01*
G01X16552Y1635303D02*
Y1638005D01*
G01X49936Y1311343D02*
X47770Y1309177D01*
Y1300424D01*
X48664Y1299530D01*
X50331D01*
G01X46980Y1335843D02*
X49936Y1332887D01*
Y1311343D01*
G01X46980Y1335843D02*
X49959Y1338822D01*
X52227D01*
G01X72180Y680710D02*
X77791D01*
X79520Y682439D01*
G01X72180Y685710D02*
X79536D01*
G01X58752Y1295869D02*
Y1295763D01*
X60873Y1293642D01*
X69377D01*
X71909Y1296174D01*
Y1299430D01*
G01X58752Y1299596D02*
Y1295869D01*
G01X50331Y1299530D02*
Y1295444D01*
X52131Y1293644D01*
X56527D01*
X58752Y1295869D01*
G01X81341Y1310698D02*
Y1305884D01*
X74887Y1299430D01*
X71909D01*
G01X54130Y1318203D02*
Y1313763D01*
G01X60289Y1770835D02*
X55544D01*
G01X60289Y1762982D02*
X55080D01*
G01X60289Y1755171D02*
X54948D01*
G01X59609Y1778371D02*
X56425D01*
G01X70376Y1801343D02*
Y1796383D01*
G01X139920Y78071D02*
X134928Y73079D01*
X115782D01*
X109899Y67196D01*
X99183D01*
X93790Y61803D01*
Y30113D01*
X95583Y28320D01*
X100778D01*
G01Y37438D02*
X97417D01*
G01X100778Y32853D02*
X97417D01*
G01X100518Y381386D02*
X96736D01*
X93159Y377809D01*
Y370244D01*
X94700Y368703D01*
X107306D01*
X117251Y358758D01*
G01X100518Y391220D02*
X97985D01*
G01X100518Y376580D02*
X97536D01*
G01X100518Y371909D02*
X97457D01*
G01X100518Y386235D02*
X100468Y386185D01*
X94882D01*
X91030Y390037D01*
Y409929D01*
X87949Y413010D01*
Y425897D01*
X107839Y445787D01*
Y700964D01*
X109219Y702344D01*
Y711263D01*
X109251Y711295D01*
G01X100518Y396024D02*
X97643D01*
G01X92980Y680710D02*
X86187D01*
G01X88681Y701593D02*
Y704108D01*
G01X81563Y708496D02*
Y705437D01*
G01X92980Y685710D02*
X86673D01*
G01X101056Y730398D02*
X95748D01*
X90612Y735534D01*
Y777207D01*
X107377Y793972D01*
Y800498D01*
X110385Y803506D01*
Y1026141D01*
X133837Y1049593D01*
Y1116082D01*
X139920Y1122165D01*
G01X109251Y711295D02*
X97951D01*
X94533Y714713D01*
Y723030D01*
X96960Y725457D01*
X101056D01*
G01Y739962D02*
X97443D01*
G01X101056Y735248D02*
X97534D01*
G01X101189Y1067515D02*
X96904D01*
G01X101189Y1092036D02*
X96948D01*
G01X101189Y1087095D02*
X96949D01*
G01X101189Y1072226D02*
X96774D01*
G01X74602Y1333203D02*
X78562D01*
X81341Y1330424D01*
Y1310698D01*
G01X100227Y1429195D02*
X96386D01*
X93821Y1426630D01*
Y1413029D01*
X108498Y1398352D01*
G01X100227Y1424340D02*
X97403D01*
G01X100227Y1419492D02*
X97825D01*
G01X100227Y1443743D02*
X96993D01*
G01X100227Y1438980D02*
X96996D01*
G01X89071Y1748227D02*
X93771D01*
G01X87057Y1764190D02*
X89948D01*
X90820Y1765062D01*
X91460D01*
G01X86266Y1771103D02*
X88837D01*
G01X88624Y1758052D02*
Y1759888D01*
X87057Y1761455D01*
Y1764190D01*
G01X101677Y1770527D02*
X99269D01*
X96049Y1767307D01*
Y1757143D01*
X113257Y1739935D01*
Y1498837D01*
X116759Y1495335D01*
X123342D01*
X128385Y1490292D01*
Y1481732D01*
X139920Y1470197D01*
G01Y1818228D02*
X125007Y1803315D01*
X115415D01*
X111879Y1806851D01*
X103054D01*
X93810Y1797607D01*
Y1779187D01*
X97483Y1775514D01*
X101677D01*
G01X75376Y1801343D02*
Y1796236D01*
G01X80376Y1801343D02*
Y1796163D01*
G01X85376Y1801343D02*
Y1796236D01*
G01X100778Y28320D02*
Y24288D01*
X100693Y24203D01*
G01X104137Y78186D02*
X104116Y78207D01*
Y82557D01*
G01X119920Y78071D02*
X119853Y78138D01*
X110417D01*
X110389Y78110D01*
X110313Y78186D01*
X107287D01*
G01X117251Y358758D02*
X113119Y354626D01*
Y86983D01*
X116761Y83341D01*
X134550D01*
X139820Y78071D01*
X139920D01*
G01X117251Y358758D02*
X126216D01*
X130978Y363520D01*
Y422771D01*
X134309Y426102D01*
X139920D01*
G01X100518Y386235D02*
Y381386D01*
G01X107668Y426104D02*
X113125D01*
X113142Y426087D01*
X114217D01*
X114232Y426102D01*
X119920D01*
G01X109251Y711295D02*
X114297D01*
X118346Y707246D01*
X141591D01*
X147167Y712822D01*
Y735862D01*
X165022Y753717D01*
Y768377D01*
X163423Y769976D01*
X156332D01*
X155113Y771195D01*
Y776673D01*
G01X101056Y720745D02*
X98591D01*
G01X101056Y715937D02*
X98564D01*
G01X101056Y730398D02*
Y725457D01*
G01X107592Y774100D02*
X107596Y774104D01*
X114655D01*
X114685Y774134D01*
X119920D01*
G01Y1122165D02*
X111235D01*
X111234Y1122166D01*
X108834D01*
G01X105684D02*
Y1125919D01*
G01X108498Y1398352D02*
Y1226062D01*
X114592Y1219968D01*
Y1130649D01*
X118155Y1127086D01*
X134999D01*
X139920Y1122165D01*
G01Y1470197D02*
X131851Y1462128D01*
Y1405479D01*
X124724Y1398352D01*
X108498D01*
G01X100227Y1434041D02*
Y1429195D01*
G01X119920Y1470197D02*
X110948D01*
X110940Y1470205D01*
X108540D01*
G01X105455Y1472894D02*
Y1470270D01*
X105390Y1470205D01*
G01X101677Y1760827D02*
X99068D01*
G01X101677Y1765722D02*
X99103D01*
G01X101677Y1770527D02*
Y1775514D01*
G01Y1785571D02*
X99047D01*
G01X101677Y1780542D02*
X98873D01*
G01X155202Y72497D02*
X145494D01*
X139920Y78071D01*
G01Y88071D02*
X155270D01*
X155366Y88167D01*
G01X156321Y418198D02*
X147824D01*
X139920Y426102D01*
G01X155113Y776673D02*
X142459D01*
X139920Y774134D01*
G01Y784134D02*
X155354D01*
X155356Y784132D01*
G01X156117Y1116127D02*
X145958D01*
X139920Y1122165D01*
G01Y1132165D02*
X155334D01*
X155347Y1132178D01*
G01X155648Y1473020D02*
X142743D01*
X139920Y1470197D01*
G01X155409Y1820360D02*
X142052D01*
X139920Y1818228D01*
G01Y1828228D02*
X155653D01*
X155656Y1828225D01*
G01X158352Y72497D02*
X161742D01*
G01X158463Y68130D02*
X162586D01*
G01X162384Y56744D02*
X159676D01*
G01X161257Y420869D02*
Y418194D01*
X161256Y418195D01*
G01X161377Y407575D02*
X158490D01*
G01X161826Y756757D02*
X158950D01*
G01X158665Y764231D02*
X161644D01*
G01X158263Y776673D02*
X159336D01*
X161131Y774878D01*
G01X159278Y1106853D02*
X162140D01*
G01X164539Y1116135D02*
X160870D01*
G01X163099Y1457084D02*
Y1457069D01*
X160252Y1457084D01*
G01X159505Y1462651D02*
X162524D01*
G01X158798Y1473020D02*
X160602D01*
X162242Y1471380D01*
G01X162140Y1807740D02*
X158840D01*
G01X158563Y1815631D02*
X163250Y1815650D01*
Y1815631D01*
G01X184284Y943579D02*
Y948331D01*
G01X184196Y962671D02*
Y967371D01*
G01X184632Y979154D02*
Y983423D01*
G01X184353Y996558D02*
Y1001556D01*
G01X184118Y1015313D02*
Y1019280D01*
G01X182329Y1025022D02*
X184173D01*
X188385Y1020810D01*
G01X263086Y151264D02*
Y147675D01*
G01X264516Y500919D02*
Y497341D01*
G01X264181Y851243D02*
Y847354D01*
G01X267194Y1195314D02*
Y1191777D01*
G01X262559Y1195314D02*
Y1191777D01*
G01X267420Y151264D02*
Y147540D01*
G01X271943Y151264D02*
Y147630D01*
G01X276523Y151264D02*
Y147585D01*
G01X271547Y256764D02*
Y260353D01*
G01X281193Y253439D02*
Y256624D01*
G01X276617Y253439D02*
Y256400D01*
G01X285513Y326517D02*
Y322688D01*
G01X281074Y326517D02*
Y322688D01*
G01X289895Y326517D02*
Y322688D01*
G01X281569Y432340D02*
Y436169D01*
G01X286665Y429015D02*
Y432844D01*
G01X291002Y429015D02*
Y432844D01*
G01X277776Y500919D02*
Y497341D01*
G01X273405Y500919D02*
Y497341D01*
G01X268938Y500919D02*
Y497341D01*
G01X285348Y606962D02*
Y610540D01*
G01X290984Y603637D02*
Y607215D01*
G01X274514Y676124D02*
Y672192D01*
G01X270109Y676124D02*
Y672192D01*
G01X283340Y676124D02*
Y672192D01*
G01X278955Y676124D02*
Y672192D01*
G01X278184Y778711D02*
Y782643D01*
G01X282737Y778711D02*
Y782643D01*
G01X273114Y782036D02*
Y785968D01*
G01X277788Y851243D02*
Y847237D01*
G01X273305Y851243D02*
Y847237D01*
G01X268686Y851243D02*
Y847488D01*
G01X285966Y955761D02*
Y959767D01*
G01X291194Y952436D02*
Y956442D01*
G01X285666Y1019882D02*
Y1016162D01*
G01X281124Y1019882D02*
Y1016162D01*
G01X290107Y1019882D02*
Y1016162D01*
G01X282958Y1130751D02*
Y1134471D01*
G01X288188Y1127426D02*
Y1131146D01*
G01X276807Y1195314D02*
Y1191777D01*
G01X272082Y1195314D02*
Y1191777D01*
G01X283808Y1305422D02*
Y1308959D01*
G01X289210Y1302097D02*
Y1305634D01*
G01X284240Y1378342D02*
Y1374544D01*
G01X279518Y1378341D02*
Y1374543D01*
G01X275052Y1378341D02*
Y1374715D01*
G01X270579Y1378341D02*
Y1374626D01*
G01X270234Y1478962D02*
Y1482760D01*
G01X275521Y1475637D02*
Y1479435D01*
G01X279990Y1475637D02*
Y1479435D01*
G01X291054Y1547451D02*
Y1543211D01*
G01X284086Y1655643D02*
Y1659883D01*
G01X289421Y1652318D02*
Y1656558D01*
G01X279703Y1726915D02*
Y1723398D01*
G01X274704Y1726915D02*
Y1723196D01*
G01X284583Y1726915D02*
Y1723465D01*
G01X289499Y1726915D02*
Y1723735D01*
G01X281066Y1829871D02*
Y1834569D01*
G01X286623Y1826546D02*
Y1829400D01*
G01X288794Y1858668D02*
X293606D01*
G01X287121Y1901895D02*
Y1898327D01*
G01X282717Y1901895D02*
Y1898327D01*
G01X278262Y1901895D02*
Y1898327D01*
G01X273817Y1901895D02*
Y1898327D01*
G01X299687Y75393D02*
Y78778D01*
G01X304151Y75393D02*
Y78778D01*
G01X308651Y75393D02*
Y78778D01*
G01X313089Y75393D02*
Y78778D01*
G01X294483Y78718D02*
Y82732D01*
G01X294506Y326517D02*
Y322688D01*
G01X295509Y603637D02*
Y607215D01*
G01X295874Y952436D02*
Y956442D01*
G01X294617Y1019882D02*
Y1016162D01*
G01X292698Y1127426D02*
Y1131146D01*
G01X294133Y1302097D02*
Y1305634D01*
G01X308636Y1513883D02*
X313894D01*
G01X304870Y1547451D02*
Y1543211D01*
G01X300392Y1547451D02*
Y1543211D01*
G01X295675Y1547451D02*
Y1543211D01*
G01X294090Y1652318D02*
Y1656558D01*
G01X291550Y1826546D02*
Y1829846D01*
G01X314562Y2004407D02*
Y2009087D01*
G01X322005Y75393D02*
Y78778D01*
G01X317567Y75393D02*
Y78778D01*
G01X320208Y1162266D02*
X325796D01*
G01X324803Y2002031D02*
Y2005272D01*
G01X320045Y2002031D02*
Y2005215D01*
X25219Y18752D03*
X3001Y52034D03*
Y100034D03*
Y150034D03*
Y200034D03*
Y250034D03*
Y300034D03*
Y350034D03*
Y400034D03*
Y450034D03*
Y500034D03*
X13441Y495961D03*
X3001Y550034D03*
X10914Y578848D03*
X15984Y578849D03*
X3001Y600034D03*
Y650034D03*
Y700034D03*
Y750034D03*
Y800034D03*
Y850034D03*
Y900034D03*
Y950034D03*
Y1000034D03*
Y1050034D03*
Y1100034D03*
Y1150034D03*
Y1200034D03*
Y1250034D03*
Y1300034D03*
Y1350034D03*
Y1400034D03*
Y1450034D03*
Y1500034D03*
Y1550034D03*
X11541Y1562330D03*
X3006Y1594602D03*
X3012Y1610165D03*
X3001Y1650034D03*
X11153Y1638435D03*
X16552Y1638005D03*
X3001Y1700034D03*
Y1750034D03*
Y1800034D03*
Y1850034D03*
Y1900034D03*
Y1950034D03*
Y2000034D03*
Y2050034D03*
X48433Y866179D03*
X48467Y869278D03*
X49441Y1238962D03*
X45581Y1278420D03*
X45413Y1283724D03*
X45244Y1289067D03*
X45350Y1299697D03*
X45267Y1294203D03*
X45281Y1310893D03*
X45244Y1305787D03*
X46980Y1335843D03*
Y1325843D03*
Y1315843D03*
Y1320843D03*
Y1330843D03*
Y1345843D03*
Y1340843D03*
X26833Y2067866D03*
X61888Y666012D03*
X57124Y675327D03*
X54483Y679810D03*
X59236Y670758D03*
X70865Y872278D03*
Y866278D03*
Y860278D03*
Y897750D03*
Y890116D03*
X60815Y1019026D03*
X63577Y1019115D03*
X59127Y1257647D03*
X57458Y1253378D03*
X58356Y1279812D03*
X58416Y1272383D03*
X54543Y1296513D03*
X63061Y1296312D03*
X67568Y1296654D03*
X61866Y1309190D03*
X54543Y1308995D03*
X67568Y1307829D03*
X54130Y1313763D03*
X70340Y1328203D03*
X61866Y1342104D03*
X55544Y1770835D03*
X55080Y1762982D03*
X54948Y1755171D03*
X56425Y1778371D03*
X70376Y1796383D03*
X75219Y18752D03*
X97417Y32853D03*
Y37438D03*
X97536Y376580D03*
X97457Y371909D03*
X97985Y391220D03*
X97643Y396024D03*
X93223Y417736D03*
X94347Y421562D03*
X86187Y680710D03*
X79520Y682439D03*
X88681Y704108D03*
X81563Y705437D03*
X86673Y685710D03*
X79536D03*
X96308Y696622D03*
X98591Y720745D03*
X98564Y715937D03*
X97443Y739962D03*
X97534Y735248D03*
X98124Y745139D03*
X95775Y751469D03*
X89338Y878294D03*
X91733Y899382D03*
X92633Y907404D03*
X91294Y926951D03*
X98139Y990959D03*
X76446Y1014871D03*
X79499D03*
X96904Y1067515D03*
X82763Y1060051D03*
X96948Y1092036D03*
X96949Y1087095D03*
X96774Y1072226D03*
X96684Y1081791D03*
X96510Y1395382D03*
X97403Y1424340D03*
X97825Y1419492D03*
X96993Y1443743D03*
X96996Y1438980D03*
X97465Y1447919D03*
X95236Y1453321D03*
X88837Y1771103D03*
X91460Y1765062D03*
X93771Y1748227D03*
X80376Y1772098D03*
Y1768566D03*
X75376Y1796236D03*
X80376Y1796163D03*
X85376Y1796236D03*
X80376Y1775609D03*
X76833Y2067866D03*
X106335Y22580D03*
X106958Y26285D03*
X108082Y38899D03*
X102646Y49461D03*
X101430Y41803D03*
X107405Y49898D03*
X107037Y34687D03*
X104350Y62293D03*
X107263Y72244D03*
X109054Y58250D03*
X104116Y82557D03*
X108672Y86150D03*
X106836Y376461D03*
X106709Y391219D03*
X105451Y406795D03*
X114498Y396207D03*
X101990Y426104D03*
X109475Y434743D03*
X111017Y419566D03*
X102960Y672823D03*
X113018Y706356D03*
X107025Y725368D03*
X105087Y754126D03*
X106935Y745139D03*
X107173Y735219D03*
X101244Y774100D03*
X112836Y769122D03*
X111967Y795261D03*
X115139Y849240D03*
X105395Y972040D03*
X102611Y972220D03*
X100687Y999391D03*
X107351Y1093484D03*
X107235Y1081791D03*
X107215Y1072208D03*
X98652Y1096403D03*
X108779Y1105760D03*
X105152Y1118381D03*
X112503Y1115860D03*
X105684Y1125919D03*
X108468Y1129286D03*
X100719Y1312810D03*
Y1306810D03*
Y1330810D03*
Y1336810D03*
Y1324810D03*
Y1318810D03*
Y1346065D03*
X106962Y1434041D03*
X106921Y1419492D03*
X106763Y1444599D03*
X107006Y1452651D03*
X105455Y1472894D03*
X108574Y1463389D03*
X113518Y1489571D03*
X99103Y1765722D03*
X99068Y1760827D03*
X107355Y1770437D03*
X99047Y1785571D03*
X98873Y1780542D03*
X99294Y1789947D03*
X107391Y1794460D03*
X107220Y1791589D03*
X107373Y1780544D03*
X105669Y1815227D03*
X108819Y1812118D03*
X106819Y1802230D03*
X108819Y1824470D03*
X109991Y2083607D03*
X125219Y3002D03*
X144878Y1738861D03*
X162384Y56744D03*
X157558Y51426D03*
X161742Y72497D03*
X162586Y68130D03*
X161339Y88108D03*
X159417Y91281D03*
X158901Y85017D03*
X169500Y126110D03*
Y118626D03*
Y111407D03*
X166500D03*
Y118626D03*
Y126110D03*
X169329Y140623D03*
X169500Y132705D03*
X169329Y148066D03*
X166329D03*
X166500Y132705D03*
X166329Y140623D03*
X169329Y156102D03*
Y163621D03*
X166329D03*
Y156102D03*
X168975Y265783D03*
X165975D03*
X168975Y296140D03*
Y286803D03*
Y276298D03*
X165975D03*
Y286803D03*
Y296140D03*
X168975Y312307D03*
Y303868D03*
X165975D03*
Y312307D03*
X161377Y407575D03*
X156865Y401207D03*
X161517Y436119D03*
X161257Y420869D03*
X159019Y439268D03*
X158807Y432969D03*
X159430Y461714D03*
X156430D03*
X159430Y483012D03*
X159259Y490930D03*
X159430Y468933D03*
Y476417D03*
X156430D03*
Y468933D03*
X156259Y490930D03*
X156430Y483012D03*
X159259Y513928D03*
Y498373D03*
Y506409D03*
X156259D03*
Y498373D03*
Y513928D03*
X157272Y604773D03*
X160272D03*
X157272Y633416D03*
Y613574D03*
Y624079D03*
X160272D03*
Y613574D03*
Y633416D03*
X157272Y641144D03*
Y649583D03*
X160272D03*
Y641144D03*
X156610Y751063D03*
X161826Y756757D03*
X161131Y774878D03*
X161644Y764231D03*
X158956Y780982D03*
X161479Y784141D03*
X159053Y787280D03*
X158444Y822725D03*
X165872D03*
X162872D03*
X155444D03*
X165872Y830209D03*
X158444D03*
X165872Y836804D03*
X158444D03*
X165701Y844722D03*
X158273D03*
X165701Y852165D03*
X158273D03*
X155273D03*
X162701D03*
X155273Y844722D03*
X162701D03*
X155444Y836804D03*
X162872D03*
X155444Y830209D03*
X162872D03*
X165701Y860201D03*
X158273D03*
X165701Y867720D03*
X158273D03*
X155273D03*
X162701D03*
X155273Y860201D03*
X162701D03*
X163699Y972924D03*
X166699D03*
X163699Y983439D03*
Y993944D03*
X166699D03*
Y983439D03*
X163424Y1011298D03*
Y1003570D03*
Y1019737D03*
X166424D03*
Y1003570D03*
Y1011298D03*
X164539Y1116135D03*
X162140Y1106853D03*
X156854Y1101031D03*
X159382Y1136151D03*
X158456Y1129045D03*
X156124Y1176256D03*
X163552D03*
Y1183740D03*
Y1190335D03*
X156124D03*
Y1183740D03*
X163552Y1169037D03*
X156124D03*
X153124D03*
X160552D03*
X153124Y1183740D03*
Y1190335D03*
X160552D03*
Y1183740D03*
Y1176256D03*
X153124D03*
X169375Y1183740D03*
Y1190335D03*
Y1176256D03*
X163381Y1198253D03*
X155953D03*
X152953D03*
X160381D03*
X169204D03*
X158749Y1307733D03*
X155749D03*
X158749Y1328753D03*
Y1318248D03*
X155749D03*
Y1328753D03*
X158749Y1354257D03*
Y1338090D03*
Y1345818D03*
X155749D03*
Y1338090D03*
Y1354257D03*
X158618Y1399448D03*
X164037Y1400226D03*
X170351Y1401324D03*
X159192Y1451105D03*
X163099Y1457084D03*
X162524Y1462651D03*
X162242Y1471380D03*
X159216Y1477124D03*
X154109Y1499221D03*
X161537D03*
Y1506440D03*
X170360D03*
X154109D03*
X157109D03*
X164537D03*
Y1499221D03*
X157109D03*
X159526Y1483434D03*
X153938Y1528437D03*
X154109Y1513924D03*
Y1520519D03*
X170360Y1513924D03*
Y1520519D03*
X161537D03*
Y1513924D03*
X161366Y1528437D03*
X170189D03*
X164366D03*
X164537Y1513924D03*
Y1520519D03*
X157109D03*
Y1513924D03*
X156938Y1528437D03*
X153938Y1535880D03*
Y1543916D03*
Y1551435D03*
X170189Y1535880D03*
Y1543916D03*
X161366Y1535880D03*
Y1543916D03*
Y1551435D03*
X170189D03*
X164366D03*
Y1543916D03*
Y1535880D03*
X156938Y1551435D03*
Y1543916D03*
Y1535880D03*
X161492Y1667763D03*
Y1657248D03*
X158492D03*
Y1667763D03*
X161492Y1695333D03*
Y1687605D03*
Y1678268D03*
X158492D03*
Y1687605D03*
Y1695333D03*
X161492Y1703772D03*
X158492D03*
X163257Y1737619D03*
X150309Y1737009D03*
X168151Y1739208D03*
X165782Y1732903D03*
X156183Y1735240D03*
X163250Y1815631D03*
X162140Y1807740D03*
X156452Y1800821D03*
X161844Y1828225D03*
X159822Y1831380D03*
X159075Y1825087D03*
X155091Y1866003D03*
X162519D03*
X159519D03*
X152091D03*
X155091Y1880706D03*
Y1887301D03*
X162519D03*
Y1880706D03*
Y1873222D03*
X155091D03*
X152091D03*
X168342D03*
X159519D03*
Y1880706D03*
Y1887301D03*
X168342D03*
Y1880706D03*
X152091Y1887301D03*
Y1880706D03*
X154920Y1902662D03*
Y1910698D03*
X162348Y1902662D03*
Y1910698D03*
X154920Y1895219D03*
X162348D03*
X168171D03*
X159348D03*
X151920D03*
X159348Y1910698D03*
Y1902662D03*
X168171Y1910698D03*
Y1902662D03*
X151920Y1910698D03*
Y1902662D03*
X154920Y1918217D03*
X162348D03*
X168171D03*
X159348D03*
X151920D03*
X159991Y2083607D03*
X175219Y3002D03*
X176928Y126110D03*
Y118626D03*
Y111407D03*
X173928D03*
Y118626D03*
Y126110D03*
X176757Y140623D03*
X176928Y132705D03*
X176757Y148066D03*
X173757D03*
X173928Y132705D03*
X173757Y140623D03*
X176757Y156102D03*
Y163621D03*
X173757D03*
Y156102D03*
X175033Y261594D03*
Y268813D03*
X178033D03*
Y261594D03*
X175033Y282892D03*
X174862Y290810D03*
Y298253D03*
X175033Y276297D03*
X178033D03*
X177862Y298253D03*
Y290810D03*
X178033Y282892D03*
X174862Y313808D03*
Y306289D03*
X177862D03*
Y313808D03*
X182191Y822725D03*
X174695D03*
X171695D03*
X179191D03*
X174524Y844722D03*
Y852165D03*
X182191Y830209D03*
X174695D03*
X182191Y836804D03*
X174695D03*
X182020Y844722D03*
Y852165D03*
X179020D03*
Y844722D03*
X171695Y836804D03*
X179191D03*
X171695Y830209D03*
X179191D03*
X171524Y852165D03*
Y844722D03*
X174524Y860201D03*
Y867720D03*
X182020Y860201D03*
Y867720D03*
X179020D03*
Y860201D03*
X171524Y867720D03*
Y860201D03*
X184284Y948331D03*
X175989Y944537D03*
X176011Y936829D03*
X184196Y967371D03*
X175359Y963486D03*
X175561Y955964D03*
X175135Y972490D03*
X184632Y983423D03*
X175022Y980281D03*
X175742Y989958D03*
X175449Y997660D03*
X184353Y1001556D03*
X184118Y1019280D03*
X188385Y1020810D03*
X175698Y1008730D03*
X175473Y1016296D03*
X175448Y1031766D03*
X175897Y1023997D03*
X179871Y1176256D03*
Y1190335D03*
Y1183740D03*
X172375Y1176256D03*
Y1190335D03*
Y1183740D03*
X176871D03*
Y1190335D03*
Y1176256D03*
X179700Y1198253D03*
X172204D03*
X176700D03*
X176083Y1402321D03*
X177856Y1506440D03*
X173360D03*
X180856D03*
X177856Y1513924D03*
Y1520519D03*
X177685Y1528437D03*
X173189D03*
X173360Y1520519D03*
Y1513924D03*
X180685Y1528437D03*
X180856Y1520519D03*
Y1513924D03*
X177685Y1535880D03*
Y1543916D03*
Y1551435D03*
X173189D03*
Y1543916D03*
Y1535880D03*
X180685Y1551435D03*
Y1543916D03*
Y1535880D03*
X173394Y1736051D03*
X178838Y1880706D03*
Y1887301D03*
Y1873222D03*
X171342Y1880706D03*
Y1887301D03*
Y1873222D03*
X175838D03*
Y1887301D03*
Y1880706D03*
X178667Y1902662D03*
Y1910698D03*
Y1895219D03*
X171171Y1902662D03*
Y1910698D03*
Y1895219D03*
X175667D03*
Y1910698D03*
Y1902662D03*
X178667Y1918217D03*
X171171D03*
X175667D03*
X217732Y153964D03*
Y170131D03*
Y161692D03*
Y164692D03*
Y173131D03*
Y156964D03*
X219214Y1287272D03*
Y1301975D03*
X219349Y1308924D03*
X219214Y1294491D03*
X219178Y1324285D03*
Y1332321D03*
Y1316842D03*
Y1339840D03*
X219131Y1663167D03*
Y1670386D03*
Y1684465D03*
Y1677870D03*
X218960Y1692383D03*
Y1699826D03*
Y1707862D03*
Y1715381D03*
X209991Y2083607D03*
X225219Y3002D03*
X237955Y56999D03*
X240955D03*
X237955Y64483D03*
X237784Y78996D03*
X237955Y71078D03*
X240955D03*
X240784Y78996D03*
X240955Y64483D03*
X237784Y94475D03*
Y101994D03*
Y86439D03*
X240784D03*
Y101994D03*
Y94475D03*
X238741Y153964D03*
X227700D03*
X238741Y170131D03*
Y161692D03*
X227700Y170131D03*
Y161692D03*
Y164692D03*
Y173131D03*
X238741Y164692D03*
Y173131D03*
X227700Y156964D03*
X238741D03*
X241033Y244995D03*
X233537D03*
X224714Y237776D03*
Y244995D03*
X227714D03*
Y237776D03*
X236537Y244995D03*
X241033Y259074D03*
X240862Y266992D03*
Y274435D03*
X241033Y252479D03*
X233537Y259074D03*
X233366Y266992D03*
Y274435D03*
X224714Y259074D03*
X224543Y266992D03*
Y274435D03*
X233537Y252479D03*
X224714D03*
X227714D03*
X236537D03*
X227543Y274435D03*
Y266992D03*
X227714Y259074D03*
X236366Y274435D03*
Y266992D03*
X236537Y259074D03*
X240862Y289990D03*
Y282471D03*
X233366Y289990D03*
X224543D03*
X233366Y282471D03*
X224543D03*
X227543D03*
X236366D03*
X227543Y289990D03*
X236366D03*
X239746Y407393D03*
Y396878D03*
Y417898D03*
Y399878D03*
Y410393D03*
Y420898D03*
X229548Y461083D03*
X232548D03*
X238371Y482381D03*
X238200Y490299D03*
X229548Y482381D03*
X229377Y490299D03*
X238371Y468302D03*
Y475786D03*
X229548Y468302D03*
Y475786D03*
X232548D03*
Y468302D03*
X241371Y475786D03*
Y468302D03*
X232377Y490299D03*
X232548Y482381D03*
X241200Y490299D03*
X241371Y482381D03*
X238200Y513297D03*
X229377D03*
X238200Y497742D03*
X229377D03*
X238200Y505778D03*
X229377D03*
X232377D03*
X241200D03*
X232377Y497742D03*
X241200D03*
X232377Y513297D03*
X241200D03*
X227963Y608108D03*
X235391D03*
X227963Y601513D03*
X235391D03*
Y594029D03*
X227963D03*
X230963D03*
X238391D03*
Y601513D03*
X230963D03*
X238391Y608108D03*
X230963D03*
X227792Y631505D03*
X235220D03*
X227792Y623469D03*
X235220D03*
X227792Y616026D03*
X235220D03*
X238220D03*
X230792D03*
X238220Y623469D03*
X230792D03*
X238220Y631505D03*
X230792D03*
X227792Y639024D03*
X235220D03*
X238220D03*
X230792D03*
X234012Y754782D03*
X237012D03*
X234012Y762510D03*
Y770949D03*
X237012D03*
Y762510D03*
X241396Y862887D03*
Y855159D03*
Y871326D03*
X238396D03*
Y855159D03*
Y862887D03*
X231339Y959673D03*
X238767D03*
Y967157D03*
Y973752D03*
X231339D03*
Y967157D03*
X238767Y952454D03*
X231339D03*
X234339D03*
X241767D03*
X234339Y967157D03*
Y973752D03*
X241767D03*
Y967157D03*
Y959673D03*
X234339D03*
X238596Y981670D03*
X231168D03*
X238596Y997149D03*
Y989113D03*
X231168Y997149D03*
Y989113D03*
X234168D03*
Y997149D03*
X241596Y989113D03*
Y997149D03*
X234168Y981670D03*
X241596D03*
X238596Y1004668D03*
X231168D03*
X234168D03*
X241596D03*
X235709Y1124900D03*
Y1135415D03*
X232709D03*
Y1124900D03*
X242677Y1135415D03*
Y1124900D03*
X235709Y1145920D03*
X232709D03*
X242677D03*
X235659Y1215296D03*
X228231D03*
X235659Y1207777D03*
Y1199741D03*
X228231Y1207777D03*
Y1199741D03*
X231231D03*
Y1207777D03*
X238659Y1199741D03*
Y1207777D03*
X231231Y1215296D03*
X238659D03*
X226642Y1287272D03*
X222214D03*
X229642D03*
X226642Y1301975D03*
X235465D03*
X226777Y1308924D03*
X235600D03*
X242961Y1301975D03*
X243096Y1308924D03*
X226642Y1294491D03*
X235465D03*
X242961D03*
X222214D03*
X222349Y1308924D03*
X222214Y1301975D03*
X238465Y1294491D03*
X229642D03*
X238600Y1308924D03*
X229777D03*
X238465Y1301975D03*
X229642D03*
X226606Y1324285D03*
X235429D03*
X226606Y1332321D03*
X235429D03*
X242925Y1324285D03*
Y1332321D03*
X226606Y1316842D03*
X235429D03*
X242925D03*
X222178D03*
Y1332321D03*
Y1324285D03*
X238429Y1316842D03*
X229606D03*
X238429Y1332321D03*
X229606D03*
X238429Y1324285D03*
X229606D03*
X226606Y1339840D03*
X235429D03*
X242925D03*
X222178D03*
X238429D03*
X229606D03*
X235382Y1670386D03*
X226559Y1663167D03*
Y1670386D03*
X222131D03*
X229559D03*
Y1663167D03*
X238382Y1670386D03*
X222131Y1663167D03*
X242878Y1670386D03*
X235382Y1677870D03*
X235211Y1692383D03*
X235382Y1684465D03*
X226559D03*
Y1677870D03*
X226388Y1692383D03*
X221960D03*
X222131Y1677870D03*
Y1684465D03*
X229388Y1692383D03*
X229559Y1677870D03*
Y1684465D03*
X238382D03*
X238211Y1692383D03*
X238382Y1677870D03*
X242878D03*
Y1684465D03*
X242707Y1692383D03*
X235211Y1699826D03*
X226388D03*
X235211Y1715381D03*
Y1707862D03*
X226388D03*
Y1715381D03*
X221960D03*
Y1707862D03*
X229388Y1715381D03*
Y1707862D03*
X238211D03*
Y1715381D03*
X221960Y1699826D03*
X229388D03*
X238211D03*
X242707D03*
Y1707862D03*
Y1715381D03*
X226573Y2031480D03*
X236541D03*
X226573Y2020965D03*
X236541D03*
X242582D03*
Y2031480D03*
X231541Y2020965D03*
X221573D03*
X231541Y2031480D03*
X221573D03*
X226573Y2059050D03*
X236541Y2051322D03*
Y2059050D03*
X226573Y2041985D03*
Y2051322D03*
X236541Y2041985D03*
X242582Y2059050D03*
Y2051322D03*
Y2041985D03*
X231541D03*
X221573Y2051322D03*
Y2041985D03*
X231541Y2059050D03*
Y2051322D03*
X221573Y2059050D03*
X236541Y2067489D03*
X226573D03*
X242582D03*
X221573D03*
X231541D03*
X256566Y54944D03*
X264104D03*
X256566Y45572D03*
X264104D03*
Y48572D03*
X256566D03*
X245451Y56999D03*
X248451D03*
X256566Y65449D03*
X264104D03*
Y57944D03*
X256566D03*
X264104Y68449D03*
X256566D03*
X245451Y64483D03*
X245280Y78996D03*
X245451Y71078D03*
X248451D03*
X248280Y78996D03*
X248451Y64483D03*
X245280Y94475D03*
Y101994D03*
Y86439D03*
X248280D03*
Y101994D03*
Y94475D03*
X267627Y115559D03*
X256947Y128276D03*
X257125Y115559D03*
X267420Y147540D03*
X263086Y147675D03*
X256861Y153964D03*
X248083D03*
X256861Y170131D03*
Y161692D03*
X248083Y170131D03*
Y161692D03*
Y164692D03*
Y173131D03*
X256861Y164692D03*
Y173131D03*
X248083Y156964D03*
X256861D03*
X264596Y221664D03*
X252818D03*
X255818D03*
X261596D03*
X264596Y242684D03*
Y232179D03*
X252818Y242684D03*
Y232179D03*
X255818D03*
Y242684D03*
X261596Y232179D03*
Y242684D03*
X244033Y244995D03*
X264596Y268188D03*
Y259749D03*
Y252021D03*
X252818Y268188D03*
Y252021D03*
Y259749D03*
X255818D03*
Y252021D03*
Y268188D03*
X261596Y252021D03*
Y259749D03*
Y268188D03*
X244033Y252479D03*
X243862Y274435D03*
Y266992D03*
X244033Y259074D03*
X243862Y282471D03*
Y289990D03*
X266040Y407146D03*
Y396631D03*
Y417651D03*
X257572Y396630D03*
Y407145D03*
X248714Y407536D03*
Y397021D03*
X257572Y417650D03*
X248714Y418041D03*
Y400021D03*
Y410536D03*
X257572Y410145D03*
Y399630D03*
X266040Y399631D03*
Y410146D03*
X248714Y421041D03*
X257572Y420650D03*
X266040Y420651D03*
X265722Y463102D03*
X245867Y482381D03*
X245696Y490299D03*
X245867Y468302D03*
Y475786D03*
X248867D03*
Y468302D03*
X248696Y490299D03*
X248867Y482381D03*
X265737Y473680D03*
X245696Y513297D03*
Y497742D03*
Y505778D03*
X248696D03*
Y497742D03*
Y513297D03*
X264516Y497341D03*
X267166Y581440D03*
Y572639D03*
X264166D03*
Y581440D03*
X267166Y609010D03*
Y601282D03*
Y591945D03*
X264166D03*
Y601282D03*
Y609010D03*
X251710Y608108D03*
Y601513D03*
Y594029D03*
X244214Y608108D03*
Y601513D03*
Y594029D03*
X247214D03*
Y601513D03*
Y608108D03*
X254710Y594029D03*
Y601513D03*
Y608108D03*
X267166Y617449D03*
X264166D03*
X264433Y624321D03*
X267433D03*
X251539Y631505D03*
Y623469D03*
Y616026D03*
X244043Y631505D03*
Y623469D03*
Y616026D03*
X247043D03*
Y623469D03*
Y631505D03*
X254539Y616026D03*
Y623469D03*
Y631505D03*
X251539Y639024D03*
X244043D03*
X247043D03*
X254539D03*
X243980Y754782D03*
X255021D03*
X258021D03*
X246980D03*
X243980Y762510D03*
Y770949D03*
X255021Y762510D03*
Y770949D03*
X258021D03*
Y762510D03*
X246980Y770949D03*
Y762510D03*
X255837Y823626D03*
X255687Y812192D03*
X264181Y847354D03*
X253174Y855159D03*
Y862887D03*
Y871326D03*
X250174D03*
Y862887D03*
Y855159D03*
X265766Y949344D03*
X262766D03*
X265766Y967106D03*
Y959859D03*
X265621Y974386D03*
X262621D03*
X262766Y959859D03*
Y967106D03*
X255086Y959673D03*
Y973752D03*
Y967157D03*
X247590Y959673D03*
Y973752D03*
Y967157D03*
X250590D03*
Y973752D03*
Y959673D03*
X258086Y967157D03*
Y973752D03*
Y959673D03*
X265621Y990553D03*
Y982114D03*
X262621D03*
Y990553D03*
X254915Y981670D03*
Y997149D03*
Y989113D03*
X247419Y981670D03*
Y997149D03*
Y989113D03*
X250419D03*
Y997149D03*
Y981670D03*
X257915Y989113D03*
Y997149D03*
Y981670D03*
X254915Y1004668D03*
X247419D03*
X250419D03*
X257915D03*
X263473Y1124613D03*
Y1135128D03*
X245677Y1124900D03*
Y1135415D03*
X254433Y1135271D03*
Y1124756D03*
X251433D03*
Y1135271D03*
X260473Y1135128D03*
Y1124613D03*
X263473Y1145633D03*
X245677Y1145920D03*
X254433Y1145776D03*
X251433D03*
X260473Y1145633D03*
X267194Y1191777D03*
X262559D03*
X251978Y1215296D03*
X244482D03*
X251978Y1207777D03*
Y1199741D03*
X244482Y1207777D03*
Y1199741D03*
X247482D03*
Y1207777D03*
X254978Y1199741D03*
Y1207777D03*
X247482Y1215296D03*
X254978D03*
X259581Y1272430D03*
Y1282945D03*
X256581D03*
Y1272430D03*
X267622D03*
Y1282945D03*
X245961Y1294491D03*
X246096Y1308924D03*
X245961Y1301975D03*
X259581Y1293450D03*
Y1302787D03*
Y1310515D03*
X256581D03*
Y1302787D03*
Y1293450D03*
X267622Y1310515D03*
Y1302787D03*
Y1293450D03*
X245925Y1316842D03*
Y1332321D03*
Y1324285D03*
X259581Y1318954D03*
X256581D03*
X267622D03*
X245925Y1339840D03*
X260939Y1548010D03*
Y1534139D03*
Y1541055D03*
X263939D03*
Y1534139D03*
Y1548010D03*
X258564Y1621823D03*
X261564D03*
X258564Y1642843D03*
Y1632338D03*
X261564D03*
Y1642843D03*
X258564Y1668347D03*
Y1659908D03*
Y1652180D03*
X261564D03*
Y1659908D03*
Y1668347D03*
X245878Y1670386D03*
X262759Y1697613D03*
Y1676593D03*
Y1687108D03*
X251718Y1697613D03*
Y1687108D03*
Y1676593D03*
X254718D03*
Y1687108D03*
X265759D03*
Y1676593D03*
X254718Y1697613D03*
X265759D03*
X245707Y1692383D03*
X245878Y1684465D03*
Y1677870D03*
X262498Y1722140D03*
X262759Y1714678D03*
Y1706950D03*
X251457Y1722140D03*
X251718Y1714678D03*
Y1706950D03*
X265759D03*
X254718D03*
Y1714678D03*
X265759D03*
X265498Y1722140D03*
X254457D03*
X245707Y1715381D03*
Y1707862D03*
Y1699826D03*
X261639Y1819074D03*
Y1812119D03*
Y1805203D03*
X253468Y1819074D03*
Y1812119D03*
Y1805203D03*
X267396Y1812122D03*
Y1805206D03*
Y1819077D03*
X250468Y1805203D03*
Y1812119D03*
Y1819074D03*
X258639Y1805203D03*
Y1812119D03*
Y1819074D03*
X261459Y1826219D03*
X253288D03*
X261459Y1840090D03*
Y1833135D03*
X253288D03*
Y1840090D03*
X250288D03*
Y1833135D03*
X267037Y1840093D03*
Y1833138D03*
X258459Y1833135D03*
Y1840090D03*
X267037Y1826222D03*
X250288Y1826219D03*
X258459D03*
X247582Y2031480D03*
Y2020965D03*
X260337D03*
Y2031480D03*
X267115Y2020965D03*
Y2031480D03*
X255337D03*
Y2020965D03*
X247582Y2041985D03*
Y2051322D03*
Y2059050D03*
X260337Y2051322D03*
Y2059050D03*
Y2041985D03*
X267115D03*
Y2059050D03*
Y2051322D03*
X255337Y2041985D03*
Y2059050D03*
Y2051322D03*
X260337Y2067489D03*
X247582D03*
X267115D03*
X255337D03*
X259991Y2083607D03*
X275219Y3002D03*
X288102Y54944D03*
Y45572D03*
X271572Y54944D03*
X279754D03*
X271572Y45572D03*
X279754D03*
Y48572D03*
X271572D03*
X288102D03*
Y65449D03*
X271572D03*
X279754D03*
Y57944D03*
X271572D03*
X288102D03*
X279754Y68449D03*
X271572D03*
X288102D03*
X276523Y147585D03*
X271943Y147630D03*
X271547Y260353D03*
X276617Y256400D03*
X281193Y256624D03*
X285513Y322688D03*
X281074D03*
X289895D03*
X274531Y407289D03*
Y396774D03*
Y417794D03*
Y399774D03*
Y410289D03*
Y420794D03*
X281569Y436169D03*
X286665Y432844D03*
X291002D03*
X274991Y463099D03*
X277776Y497341D03*
X273405D03*
X268938D03*
X289569Y532762D03*
Y516595D03*
Y524323D03*
X278944Y581440D03*
Y572639D03*
X275944D03*
Y581440D03*
X278944Y601282D03*
Y609010D03*
Y591945D03*
X275944D03*
Y609010D03*
Y601282D03*
X285348Y610540D03*
X290984Y607215D03*
X278944Y617449D03*
X275944D03*
X276044Y624627D03*
X279044D03*
X274514Y672192D03*
X270109D03*
X283340D03*
X278955D03*
X273114Y785968D03*
X278184Y782643D03*
X282737D03*
X270070Y812192D03*
X268686Y847488D03*
X277788Y847237D03*
X273305D03*
X277544Y949344D03*
X274544D03*
X277544Y967106D03*
Y959859D03*
X277399Y974386D03*
X274399D03*
X274544Y959859D03*
Y967106D03*
X285966Y959767D03*
X291194Y956442D03*
X277399Y990553D03*
Y982114D03*
X274399D03*
Y990553D03*
X285666Y1016162D03*
X281124D03*
X290107D03*
X272821Y1124471D03*
Y1134986D03*
X269821D03*
Y1124471D03*
X282958Y1134471D03*
X288188Y1131146D03*
X272821Y1145491D03*
X269821D03*
X284182Y1184455D03*
Y1192183D03*
X287182D03*
Y1184455D03*
X276807Y1191777D03*
X272082D03*
X284182Y1200622D03*
X287182D03*
X270622Y1282945D03*
Y1272430D03*
Y1293450D03*
Y1302787D03*
Y1310515D03*
X283808Y1308959D03*
X289210Y1305634D03*
X270622Y1318954D03*
X284240Y1374544D03*
X279518Y1374543D03*
X275052Y1374715D03*
X270579Y1374626D03*
X275521Y1479435D03*
X279990D03*
X270234Y1482760D03*
X275400Y1548190D03*
X268534Y1548010D03*
X282995Y1548190D03*
X275400Y1534319D03*
Y1541235D03*
X268534Y1534139D03*
Y1541055D03*
X282995Y1534319D03*
Y1541235D03*
X285995D03*
Y1534319D03*
X271534Y1541055D03*
Y1534139D03*
X278400Y1541235D03*
Y1534319D03*
X285995Y1548190D03*
X271534Y1548010D03*
X278400Y1548190D03*
X291054Y1543211D03*
X270342Y1621823D03*
X273342D03*
X270342Y1642843D03*
Y1632338D03*
X273342D03*
Y1642843D03*
X270342Y1668347D03*
Y1652180D03*
Y1659908D03*
X273342D03*
Y1652180D03*
Y1668347D03*
X284086Y1659883D03*
X289421Y1656558D03*
X279703Y1723398D03*
X284583Y1723465D03*
X289499Y1723735D03*
X274704Y1723196D03*
X270396Y1819077D03*
Y1805206D03*
Y1812122D03*
X270037Y1826222D03*
Y1833138D03*
Y1840093D03*
X281066Y1834569D03*
X291550Y1829846D03*
X286623Y1829400D03*
X280240Y1858668D03*
X279976Y1864565D03*
X287121Y1898327D03*
X282717D03*
X278262D03*
X273817D03*
X272115Y2031480D03*
Y2020965D03*
Y2051322D03*
Y2059050D03*
Y2041985D03*
Y2067489D03*
X299687Y78778D03*
X304151D03*
X308651D03*
X313089D03*
X294483Y82732D03*
X308057Y248863D03*
X306267Y241010D03*
X314914Y238162D03*
X314940Y252083D03*
X294506Y322688D03*
X300537Y516309D03*
X307966Y516419D03*
Y524147D03*
X300537Y524037D03*
Y532476D03*
X307966Y532586D03*
X292569Y524323D03*
Y516595D03*
Y532762D03*
X304966Y532586D03*
X297537Y532476D03*
Y524037D03*
X304966Y524147D03*
Y516419D03*
X297537Y516309D03*
X313791Y532871D03*
Y516704D03*
Y524432D03*
X295509Y607215D03*
X315187Y652457D03*
X304146D03*
X307146D03*
X315187Y661258D03*
X304146D03*
Y681100D03*
X315187D03*
Y671763D03*
X304146D03*
X307146D03*
Y681100D03*
Y661258D03*
X315187Y688828D03*
X304146D03*
Y697267D03*
X315187D03*
X307146D03*
Y688828D03*
X295874Y956442D03*
X310194Y1020657D03*
X310078Y1007303D03*
X310274Y1001286D03*
X310143Y1014094D03*
X307143D03*
X307274Y1001286D03*
X307078Y1007303D03*
X307194Y1020657D03*
X294617Y1016162D03*
X310129Y1027081D03*
X309999Y1033718D03*
X306999D03*
X307129Y1027081D03*
X309678Y1053262D03*
X292698Y1131146D03*
X312527Y1162266D03*
X309159Y1184526D03*
Y1192254D03*
X300691Y1184526D03*
X292721Y1184312D03*
Y1192040D03*
X300691Y1192254D03*
X303691D03*
X295721Y1192040D03*
Y1184312D03*
X303691Y1184526D03*
X312159Y1192254D03*
Y1184526D03*
X312698Y1172804D03*
X309159Y1200693D03*
X300691D03*
X292721Y1200479D03*
X295721D03*
X303691Y1200693D03*
X312159D03*
X294133Y1305634D03*
X314183Y1403423D03*
X312823Y1472957D03*
X312464Y1480102D03*
X312823Y1466002D03*
Y1459086D03*
X295715Y1480099D03*
X295895Y1472954D03*
X304066D03*
X303886Y1480099D03*
X295895Y1459083D03*
Y1465999D03*
X304066D03*
Y1459083D03*
X301066D03*
Y1465999D03*
X292895D03*
Y1459083D03*
X300886Y1480099D03*
X301066Y1472954D03*
X292895D03*
X292715Y1480099D03*
X309823Y1459086D03*
Y1466002D03*
X309464Y1480102D03*
X309823Y1472957D03*
X312464Y1493973D03*
Y1487018D03*
X295715Y1487015D03*
Y1493970D03*
X303886D03*
Y1487015D03*
X300886D03*
Y1493970D03*
X292715D03*
Y1487015D03*
X309464Y1487018D03*
Y1493973D03*
X313894Y1513883D03*
X302267Y1524401D03*
X301734Y1513883D03*
X304870Y1543211D03*
X300392D03*
X295675D03*
X312077Y1575871D03*
X294090Y1656558D03*
X292614Y1864565D03*
X293606Y1858668D03*
X295754Y1917148D03*
X303349D03*
X295754Y1910232D03*
X303349D03*
X310215Y1910412D03*
X314810D03*
X307215D03*
X300349Y1910232D03*
X292754D03*
X300349Y1917148D03*
X292754D03*
X310215Y1917328D03*
X295754Y1924103D03*
X303349D03*
X310215Y1924283D03*
X307215D03*
X314810D03*
X300349Y1924103D03*
X292754D03*
X307215Y1917328D03*
X314810D03*
X314562Y2009087D03*
X309991Y2083607D03*
X325219Y3002D03*
X331403Y51409D03*
X333889Y56021D03*
X338227Y61559D03*
X322005Y78778D03*
X317567D03*
X320372Y225979D03*
X318088Y231820D03*
X321899Y238137D03*
X331046Y232021D03*
X320961Y250105D03*
X324709Y231580D03*
X332775Y318634D03*
X332693Y311980D03*
X329693D03*
X329775Y318634D03*
X332775Y335272D03*
Y342461D03*
Y325935D03*
X329775D03*
Y342461D03*
Y335272D03*
X332685Y348655D03*
X329685D03*
X335522Y404033D03*
X323313Y418313D03*
X326196Y413982D03*
X328950Y409216D03*
X320980Y423225D03*
X325139Y516632D03*
Y524360D03*
X316791Y524432D03*
Y516704D03*
Y532871D03*
X325139Y532799D03*
X322139D03*
Y524360D03*
Y516632D03*
X336617Y577978D03*
X319305Y582111D03*
X329636Y584715D03*
X317724Y588250D03*
X337387Y586230D03*
X320380Y576491D03*
X331867Y589810D03*
X333750Y595326D03*
X321742Y599041D03*
X318187Y652457D03*
Y671763D03*
Y681100D03*
Y661258D03*
Y697267D03*
Y688828D03*
X331568Y752967D03*
X339012Y752859D03*
X329336Y762693D03*
X334010Y758588D03*
X327524Y758020D03*
X329938Y948756D03*
X332527Y943746D03*
X324098Y946104D03*
X318557Y941178D03*
X323868Y929978D03*
X326646Y939788D03*
X336160Y937262D03*
X328583Y933262D03*
X321425Y951577D03*
X321235Y1020657D03*
X321315Y1001286D03*
X321119Y1007303D03*
X321184Y1014094D03*
X318184D03*
X318119Y1007303D03*
X318315Y1001286D03*
X318235Y1020657D03*
X321170Y1027081D03*
X321040Y1033718D03*
X318040D03*
X318170Y1027081D03*
X324246Y1051786D03*
X335677Y1048904D03*
X317592Y1053050D03*
X337509Y1109598D03*
X328989Y1121090D03*
X326558Y1126368D03*
X325796Y1162266D03*
X317936Y1192253D03*
Y1184525D03*
X320936D03*
Y1192253D03*
X323403Y1172804D03*
X317936Y1200692D03*
X320936D03*
X327452Y1279447D03*
X321978Y1282086D03*
X329619Y1284016D03*
X327932Y1289221D03*
X325636Y1399114D03*
X334646Y1400804D03*
X323720Y1570924D03*
X333474Y1566686D03*
X335963Y1573797D03*
X323813Y1753231D03*
X329887Y1752081D03*
X317810Y1910412D03*
X332399Y1926787D03*
X317810Y1917328D03*
Y1924283D03*
X324803Y2005272D03*
X320045Y2005215D03*
X359931Y52189D03*
X348289Y50863D03*
X345089Y56190D03*
X340373Y51579D03*
X343816Y318634D03*
X343734Y311980D03*
X340734D03*
X340816Y318634D03*
X361799Y311938D03*
X343816Y335272D03*
Y342461D03*
Y325935D03*
X340816D03*
Y342461D03*
Y335272D03*
X362236Y324983D03*
X343726Y348655D03*
X340726D03*
X342097Y401684D03*
X363825Y401768D03*
X342900Y580126D03*
X354000Y652170D03*
X356559Y675167D03*
X362577Y752783D03*
X344109Y751809D03*
X343656Y933725D03*
X345578Y1047844D03*
X344099Y1106798D03*
X363169Y1329686D03*
X351391D03*
X354391D03*
X363169Y1350706D03*
Y1360043D03*
Y1340201D03*
X351391Y1350706D03*
Y1360043D03*
Y1340201D03*
X354391D03*
Y1360043D03*
Y1350706D03*
X363169Y1376210D03*
Y1367771D03*
X351391Y1376210D03*
Y1367771D03*
X354391D03*
Y1376210D03*
X344130Y1401670D03*
X350690Y1403243D03*
X348710Y1570187D03*
X361011Y1568890D03*
X343402Y1572080D03*
X348245Y1575241D03*
X355364Y1570990D03*
X352337Y1887285D03*
X345537Y1916558D03*
X344402Y1911123D03*
X363361Y1918313D03*
X358318Y1920680D03*
X363411Y1923459D03*
X340336Y1922409D03*
X359991Y2083607D03*
X375219Y3002D03*
X372204Y56126D03*
X379257Y52158D03*
X387524Y76847D03*
X374442Y406857D03*
X374542Y401282D03*
X368907Y404308D03*
X376654Y754748D03*
X382892Y767710D03*
X386790Y774338D03*
X379335Y1189778D03*
X383276Y1184136D03*
X386816Y1179841D03*
X376472Y1194999D03*
X373674Y1199967D03*
X371523Y1204725D03*
X366169Y1329686D03*
Y1340201D03*
Y1360043D03*
Y1350706D03*
X373564Y1352548D03*
X366169Y1367771D03*
Y1376210D03*
X374681Y1365620D03*
X367829Y1566108D03*
X366306Y1899864D03*
X374431Y1901397D03*
X374775Y1919243D03*
X379403Y1917261D03*
X369748Y1921795D03*
X402512Y17108D03*
Y67108D03*
Y117108D03*
Y167108D03*
Y217108D03*
Y267108D03*
Y317108D03*
Y367108D03*
Y417108D03*
Y467108D03*
Y517108D03*
Y567108D03*
Y617108D03*
Y667108D03*
Y717108D03*
Y767108D03*
Y817108D03*
Y867108D03*
Y917108D03*
Y967108D03*
Y1017108D03*
Y1067108D03*
Y1117108D03*
Y1167108D03*
Y1217108D03*
Y1267108D03*
Y1317108D03*
Y1367108D03*
Y1417108D03*
Y1467108D03*
Y1517108D03*
Y1567108D03*
Y1617108D03*
Y1667108D03*
Y1717108D03*
Y1767108D03*
Y1817108D03*
Y1867108D03*
Y1917108D03*
Y1967108D03*
Y2017108D03*
Y2067108D03*
G54D21*
X23402Y1668874D03*
Y1685410D03*
Y1701945D03*
Y1718480D03*
Y1735016D03*
Y1751551D03*
Y1768087D03*
Y1784622D03*
Y1817693D03*
Y1801158D03*
X45056Y1668874D03*
Y1685410D03*
Y1701945D03*
Y1718480D03*
Y1735016D03*
Y1751551D03*
Y1768087D03*
Y1784622D03*
Y1801158D03*
G54D30*
X56337Y878761D03*
X388591Y62106D03*
X385616Y1991570D03*
G54D12*
X22756Y113818D03*
X22480Y316838D03*
Y328649D03*
X22756Y1866819D03*
Y1948818D03*
Y2023818D03*
G54D40*
X271547Y250964D03*
Y256764D03*
X281569Y426540D03*
Y432340D03*
X285348Y601162D03*
Y606962D03*
X273114Y776236D03*
Y782036D03*
X285966Y949961D03*
Y955761D03*
X282958Y1124951D03*
Y1130751D03*
X283808Y1299622D03*
Y1305422D03*
X270234Y1473162D03*
Y1478962D03*
X284086Y1649843D03*
Y1655643D03*
X281066Y1824071D03*
Y1829871D03*
X294483Y72918D03*
Y78718D03*
X314562Y1998607D03*
Y2004407D03*
G54D31*
X74602Y1333203D03*
Y1328203D03*
Y1323203D03*
Y1318203D03*
X54130D03*
Y1323203D03*
Y1328203D03*
Y1333203D03*
G54D13*
X22756Y125629D03*
X22480Y340460D03*
X22756Y1878630D03*
Y1960629D03*
Y2035629D03*
G54D22*
X45411Y505996D03*
Y568004D03*
Y1564000D03*
Y1626008D03*
G54D32*
X60289Y1770835D03*
X67769D03*
X60289Y1762982D03*
X67769D03*
X60289Y1755171D03*
X67769D03*
X89071Y1748227D03*
X81591D03*
X87057Y1764190D03*
X79577D03*
G54D41*
X307086Y308267D03*
G54D14*
X13441Y501915D03*
Y498765D03*
X10914Y576211D03*
Y573061D03*
X15984Y576277D03*
Y573127D03*
X11153Y1635435D03*
Y1632285D03*
X16552Y1635303D03*
Y1632153D03*
X58752Y1302746D03*
Y1299596D03*
X50331Y1302680D03*
Y1299530D03*
X71909Y1302580D03*
Y1299430D03*
X67568Y1302581D03*
Y1299431D03*
X63061Y1302746D03*
Y1299596D03*
X54543Y1302681D03*
Y1299531D03*
X52227Y1341972D03*
Y1338822D03*
X88681Y701593D03*
Y698443D03*
X92860D03*
Y701593D03*
X80269D03*
Y698443D03*
X84533D03*
Y701593D03*
X84417Y1754902D03*
Y1758052D03*
X88624D03*
Y1754902D03*
X80349D03*
Y1758052D03*
X107268Y78205D03*
X107263Y75055D03*
Y78205D03*
X107268Y81355D03*
X107668Y429254D03*
Y426104D03*
Y422954D03*
Y426104D03*
X107615Y777299D03*
Y774149D03*
X107617Y771001D03*
Y774151D03*
X108819Y1119015D03*
X108816Y1125313D03*
Y1122163D03*
X108819Y1122165D03*
X108573Y1473357D03*
Y1470207D03*
X108574Y1467057D03*
Y1470207D03*
X108819Y1818228D03*
Y1815078D03*
Y1818228D03*
Y1821378D03*
X155370Y91281D03*
Y88131D03*
X155366Y85017D03*
Y88167D03*
X156321Y418198D03*
Y415048D03*
X161256Y418195D03*
Y415045D03*
X155351Y439268D03*
Y436118D03*
X155348Y432969D03*
Y436119D03*
X155356Y780982D03*
X155362Y787280D03*
Y784130D03*
X155356Y784132D03*
X156117Y1116127D03*
Y1112977D03*
X160870Y1116135D03*
Y1112985D03*
X155264Y1135344D03*
Y1132194D03*
X155263Y1129045D03*
Y1132195D03*
X155834Y1480274D03*
X155816Y1477124D03*
Y1480274D03*
X155834Y1483424D03*
X155570Y1831380D03*
Y1828230D03*
X155561Y1825087D03*
Y1828237D03*
X263086Y151264D03*
X267420D03*
X263086Y154414D03*
X267420D03*
X264516Y500919D03*
Y504069D03*
X264181Y851243D03*
Y854393D03*
X267194Y1195314D03*
Y1198464D03*
X262559Y1195314D03*
Y1198464D03*
X271943Y151264D03*
X276523D03*
X271943Y154414D03*
X276523D03*
X276617Y253439D03*
Y250289D03*
X281193Y253439D03*
Y250289D03*
X281074Y326517D03*
Y329667D03*
X289895Y326517D03*
Y329667D03*
X285513Y326517D03*
Y329667D03*
X291002Y429015D03*
Y425865D03*
X286665Y429015D03*
Y425865D03*
X273405Y500919D03*
Y504069D03*
X268938Y500919D03*
Y504069D03*
X277776Y500919D03*
Y504069D03*
X290984Y603637D03*
Y600487D03*
X283340Y676124D03*
Y679274D03*
X278955Y676124D03*
Y679274D03*
X274514Y676124D03*
Y679274D03*
X270109Y676124D03*
Y679274D03*
X278184Y778711D03*
Y775561D03*
X282737Y778711D03*
Y775561D03*
X277788Y851243D03*
X273305D03*
X268686D03*
X277788Y854393D03*
X273305D03*
X268686D03*
X291194Y949286D03*
Y952436D03*
X290107Y1019882D03*
X285666D03*
X281124D03*
X290107Y1023032D03*
X285666D03*
X281124D03*
X288188Y1127426D03*
Y1124276D03*
X276807Y1195314D03*
Y1198464D03*
X272082Y1195314D03*
Y1198464D03*
X289210Y1302097D03*
Y1298947D03*
X284240Y1378342D03*
Y1381492D03*
X279518Y1378341D03*
Y1381491D03*
X275052Y1378341D03*
Y1381491D03*
X270579Y1378341D03*
Y1381491D03*
X275521Y1475637D03*
Y1472487D03*
X279990Y1475637D03*
Y1472487D03*
X291054Y1547451D03*
Y1550601D03*
X289421Y1649168D03*
Y1652318D03*
X289499Y1726915D03*
Y1730065D03*
X284583Y1726915D03*
Y1730065D03*
X274704Y1726915D03*
Y1730065D03*
X279703Y1726915D03*
Y1730065D03*
X286623Y1826546D03*
Y1823396D03*
X291550Y1826546D03*
Y1823396D03*
X287121Y1901895D03*
Y1905045D03*
X282717Y1901895D03*
Y1905045D03*
X278262Y1901895D03*
Y1905045D03*
X273817Y1901895D03*
Y1905045D03*
X304151Y75393D03*
Y72243D03*
X308651Y75393D03*
Y72243D03*
X313089Y75393D03*
Y72243D03*
X299687Y75393D03*
Y72243D03*
X294506Y326517D03*
Y329667D03*
X295509Y603637D03*
Y600487D03*
X295874Y949286D03*
Y952436D03*
X294617Y1019882D03*
Y1023032D03*
X292698Y1127426D03*
Y1124276D03*
X294133Y1302097D03*
Y1298947D03*
X304870Y1547451D03*
Y1550601D03*
X295675Y1547451D03*
Y1550601D03*
X300392Y1547451D03*
Y1550601D03*
X294090Y1649168D03*
Y1652318D03*
X317567Y75393D03*
Y72243D03*
X322005Y75393D03*
Y72243D03*
X320045Y2002031D03*
Y1998881D03*
X324803Y2002031D03*
Y1998881D03*
G54D23*
X45789Y896341D03*
X46023Y904215D03*
X48085Y919992D03*
X45981Y911910D03*
X47835Y960098D03*
X47109Y975598D03*
X48203Y1022325D03*
X47474Y1061692D03*
X47833Y1085626D03*
X47665Y1075692D03*
X47414Y1114586D03*
X47540Y1136770D03*
X46992Y1129235D03*
X47077Y1121658D03*
X46320Y1215867D03*
X49856Y1208711D03*
X45815Y1202354D03*
X46566Y1194825D03*
X46404Y1231610D03*
X45718Y1242795D03*
X49936Y1311343D03*
X65354Y101180D03*
X55511Y105117D03*
X51574Y114960D03*
X55511Y124803D03*
X65354Y128740D03*
Y451180D03*
X55511Y455117D03*
X51574Y464960D03*
X55511Y474803D03*
X65354Y478740D03*
Y801180D03*
X55511Y805117D03*
X51574Y814960D03*
X55511Y824803D03*
X65354Y828740D03*
X51149Y967593D03*
X51960Y953195D03*
X65354Y1151180D03*
X55511Y1155117D03*
X51574Y1164960D03*
X55511Y1174803D03*
X65354Y1178740D03*
X55496Y1235735D03*
X54654Y1244744D03*
X65354Y1501180D03*
X55511Y1505117D03*
X51574Y1514960D03*
X55511Y1524803D03*
X65354Y1528740D03*
X64356Y1788075D03*
X65354Y1851180D03*
X55511Y1855117D03*
X51574Y1864960D03*
X55511Y1874803D03*
X65354Y1878740D03*
X75197Y105117D03*
Y124803D03*
X79134Y114960D03*
Y464960D03*
X75197Y455117D03*
Y474803D03*
X93165Y706331D03*
X75197Y805117D03*
Y824803D03*
X79134Y814960D03*
Y1164960D03*
X75197Y1155117D03*
Y1174803D03*
X81341Y1310698D03*
X75197Y1505117D03*
Y1524803D03*
X79134Y1514960D03*
X75198Y1750574D03*
X92026Y1774879D03*
X79134Y1864960D03*
X75197Y1855117D03*
Y1874803D03*
X100595Y690710D03*
X307086Y113385D03*
X297243Y117322D03*
X293306Y127165D03*
X297243Y137008D03*
X307086Y140945D03*
Y463385D03*
X297243Y467322D03*
X293306Y477165D03*
X297243Y487008D03*
X307086Y490945D03*
Y813385D03*
X297243Y817322D03*
X293306Y827165D03*
X297243Y837008D03*
X307086Y840945D03*
Y1329724D03*
X297243Y1333661D03*
X293306Y1343504D03*
X297243Y1353347D03*
X307086Y1357284D03*
Y1679724D03*
X297243Y1683661D03*
X293306Y1693504D03*
X297243Y1703347D03*
X307086Y1707284D03*
X307087Y2029723D03*
X297244Y2033660D03*
X293307Y2043503D03*
X297244Y2053346D03*
X307087Y2057283D03*
X320866Y127165D03*
X316929Y117322D03*
Y137008D03*
Y467322D03*
Y487008D03*
X320866Y477165D03*
Y827165D03*
X316929Y817322D03*
Y837008D03*
Y1333661D03*
Y1353347D03*
X320866Y1343504D03*
Y1693504D03*
X316929Y1683661D03*
Y1703347D03*
X316930Y2033660D03*
Y2053346D03*
X320867Y2043503D03*
G54D33*
X70376Y1780543D03*
Y1801343D03*
X85376Y1780543D03*
X80376D03*
X75376D03*
Y1801343D03*
X80376D03*
X85376D03*
G54D42*
X307086Y1883071D03*
G54D24*
X45056Y1817693D03*
G54D15*
X14073Y512197D03*
Y522000D03*
Y552000D03*
Y561803D03*
Y1580004D03*
Y1570201D03*
Y1610004D03*
Y1619807D03*
X30473Y102007D03*
Y137440D03*
X30197Y305027D03*
Y352271D03*
X30473Y1855008D03*
Y1890441D03*
Y1937007D03*
Y1972440D03*
Y2012007D03*
Y2047440D03*
X65254Y519500D03*
Y529500D03*
Y539500D03*
X55254Y524500D03*
Y534500D03*
X65254Y549500D03*
X55254Y544500D03*
X65254Y1577504D03*
Y1587504D03*
Y1597504D03*
X55254Y1582504D03*
Y1592504D03*
Y1602504D03*
X65254Y1607504D03*
G54D16*
X30254Y514500D03*
Y559500D03*
Y1572504D03*
Y1617504D03*
G54D43*
X359842Y78780D03*
Y253780D03*
Y428779D03*
Y603779D03*
Y778780D03*
Y953780D03*
Y1128779D03*
Y1303780D03*
Y1478780D03*
Y1653780D03*
Y1828779D03*
Y2003780D03*
G54D34*
X87363Y708496D03*
X81563D03*
G54D25*
X64979Y35500D03*
Y45500D03*
Y55500D03*
X54979Y40500D03*
Y50500D03*
X64979Y65500D03*
X54979Y60500D03*
X64979Y171500D03*
X54979Y176500D03*
X64979Y181500D03*
Y191500D03*
Y201500D03*
X54979Y186500D03*
Y196500D03*
X64979Y244500D03*
X54979Y249500D03*
X64979Y254500D03*
Y264500D03*
Y274500D03*
X54979Y259500D03*
Y269500D03*
X64979Y380500D03*
Y390500D03*
X54979Y385500D03*
Y395500D03*
X64979Y400500D03*
Y410500D03*
X54979Y405500D03*
X189762Y73105D03*
X190289Y152050D03*
X190357Y247568D03*
X190817Y331786D03*
X189761Y421732D03*
X190553Y506517D03*
X192888Y598130D03*
X190816Y681645D03*
X191846Y774526D03*
X191606Y856244D03*
X196311Y947202D03*
X195516Y1032544D03*
X191250Y1122856D03*
X191342Y1206233D03*
X191846Y1299104D03*
X190552Y1380966D03*
X189463Y1474162D03*
X191079Y1557277D03*
X192143Y1648177D03*
X191607Y1731351D03*
X191530Y1823227D03*
X190289Y1900420D03*
X192125Y1998730D03*
X191530Y2043388D03*
G54D44*
G01X75376Y1774512D02*
Y1780543D01*
G01X80376D02*
Y1775609D01*
G54D26*
X54979Y70500D03*
Y206500D03*
Y279500D03*
Y415500D03*
X203542Y73105D03*
X204069Y152050D03*
X204137Y247568D03*
X204597Y331786D03*
X203541Y421732D03*
X204333Y506517D03*
X206668Y598130D03*
X204596Y681645D03*
X205626Y774526D03*
X205386Y856244D03*
X210091Y947202D03*
X209296Y1032544D03*
X205030Y1122856D03*
X205122Y1206233D03*
X205626Y1299104D03*
X204332Y1380966D03*
X203243Y1474162D03*
X204859Y1557277D03*
X205923Y1648177D03*
X205387Y1731351D03*
X205310Y1823227D03*
X204069Y1900420D03*
X205905Y1998730D03*
X205310Y2043388D03*
G54D35*
X119920Y18071D03*
Y28071D03*
Y38071D03*
Y48071D03*
Y58071D03*
Y68071D03*
Y78071D03*
Y88071D03*
Y98071D03*
Y108071D03*
Y118071D03*
Y128071D03*
Y138071D03*
Y148071D03*
Y158071D03*
Y168071D03*
Y178071D03*
Y188071D03*
Y198071D03*
Y208071D03*
Y218071D03*
Y228071D03*
Y238071D03*
Y248071D03*
Y258071D03*
Y268071D03*
Y278071D03*
Y288071D03*
Y298071D03*
Y308071D03*
Y318071D03*
Y366102D03*
Y376102D03*
Y386102D03*
Y396102D03*
Y406102D03*
Y416102D03*
Y426102D03*
Y436102D03*
Y446102D03*
Y456102D03*
Y466102D03*
Y476102D03*
Y486102D03*
Y496102D03*
Y506102D03*
Y516102D03*
Y526102D03*
Y536102D03*
Y546102D03*
Y556102D03*
Y566102D03*
Y576102D03*
Y586102D03*
Y596102D03*
Y606102D03*
Y616102D03*
Y626102D03*
Y636102D03*
Y646102D03*
Y656102D03*
Y666102D03*
Y714134D03*
Y724134D03*
Y734134D03*
Y744134D03*
Y754134D03*
Y764134D03*
Y774134D03*
Y784134D03*
Y794134D03*
Y804134D03*
Y814134D03*
Y824134D03*
Y834134D03*
Y844134D03*
Y854134D03*
Y864134D03*
Y874134D03*
Y884134D03*
Y894134D03*
Y904134D03*
Y914134D03*
Y924134D03*
Y934134D03*
Y944134D03*
Y954134D03*
Y964134D03*
Y974134D03*
Y984134D03*
Y994134D03*
Y1004134D03*
Y1014134D03*
Y1062165D03*
Y1072165D03*
Y1082165D03*
Y1092165D03*
Y1102165D03*
Y1112165D03*
Y1122165D03*
Y1132165D03*
Y1142165D03*
Y1152165D03*
Y1162165D03*
Y1172165D03*
Y1182165D03*
Y1192165D03*
Y1202165D03*
Y1212165D03*
Y1222165D03*
Y1232165D03*
Y1242165D03*
Y1252165D03*
Y1262165D03*
Y1272165D03*
Y1282165D03*
Y1292165D03*
Y1302165D03*
Y1312165D03*
Y1322165D03*
Y1332165D03*
Y1342165D03*
Y1352165D03*
Y1362165D03*
Y1410197D03*
Y1420197D03*
Y1430197D03*
Y1440197D03*
Y1450197D03*
Y1460197D03*
Y1470197D03*
Y1480197D03*
Y1490197D03*
Y1500197D03*
Y1510197D03*
Y1520197D03*
Y1530197D03*
Y1540197D03*
Y1550197D03*
Y1560197D03*
Y1570197D03*
Y1580197D03*
Y1590197D03*
Y1600197D03*
Y1610197D03*
Y1620197D03*
Y1630197D03*
Y1640197D03*
Y1650197D03*
Y1660197D03*
Y1670197D03*
Y1680197D03*
Y1690197D03*
Y1700197D03*
Y1710197D03*
Y1758228D03*
Y1768228D03*
Y1778228D03*
Y1788228D03*
Y1798228D03*
Y1808228D03*
Y1818228D03*
Y1828228D03*
Y1838228D03*
Y1848228D03*
Y1858228D03*
Y1868228D03*
Y1878228D03*
Y1888228D03*
Y1898228D03*
Y1908228D03*
Y1918228D03*
Y1928228D03*
Y1938228D03*
Y1948228D03*
Y1958228D03*
Y1968228D03*
Y1978228D03*
Y1988228D03*
Y1998228D03*
Y2008228D03*
Y2018228D03*
Y2028228D03*
Y2038228D03*
Y2048228D03*
Y2058228D03*
X139920Y28071D03*
Y18071D03*
Y58071D03*
Y48071D03*
Y38071D03*
Y78071D03*
Y68071D03*
Y98071D03*
Y88071D03*
Y128071D03*
Y118071D03*
Y108071D03*
Y148071D03*
Y138071D03*
Y178071D03*
Y168071D03*
Y158071D03*
Y198071D03*
Y188071D03*
Y228071D03*
Y218071D03*
Y208071D03*
Y248071D03*
Y238071D03*
Y268071D03*
Y258071D03*
Y298071D03*
Y288071D03*
Y278071D03*
Y318071D03*
Y308071D03*
Y328071D03*
Y366102D03*
Y396102D03*
Y386102D03*
Y376102D03*
Y416102D03*
Y406102D03*
Y436102D03*
Y426102D03*
Y466102D03*
Y456102D03*
Y446102D03*
Y486102D03*
Y476102D03*
Y516102D03*
Y506102D03*
Y496102D03*
Y536102D03*
Y526102D03*
Y566102D03*
Y556102D03*
Y546102D03*
Y586102D03*
Y576102D03*
Y606102D03*
Y596102D03*
Y636102D03*
Y626102D03*
Y616102D03*
Y656102D03*
Y646102D03*
Y676102D03*
Y666102D03*
Y734134D03*
Y724134D03*
Y714134D03*
Y754134D03*
Y744134D03*
Y774134D03*
Y764134D03*
Y804134D03*
Y794134D03*
Y784134D03*
Y824134D03*
Y814134D03*
Y854134D03*
Y844134D03*
Y834134D03*
Y874134D03*
Y864134D03*
Y904134D03*
Y894134D03*
Y884134D03*
Y924134D03*
Y914134D03*
Y944134D03*
Y934134D03*
Y974134D03*
Y964134D03*
Y954134D03*
Y994134D03*
Y984134D03*
Y1024134D03*
Y1014134D03*
Y1004134D03*
Y1072165D03*
Y1062165D03*
Y1092165D03*
Y1082165D03*
Y1122165D03*
Y1112165D03*
Y1102165D03*
Y1142165D03*
Y1132165D03*
Y1162165D03*
Y1152165D03*
Y1192165D03*
Y1182165D03*
Y1172165D03*
Y1212165D03*
Y1202165D03*
Y1242165D03*
Y1232165D03*
Y1222165D03*
Y1262165D03*
Y1252165D03*
Y1282165D03*
Y1272165D03*
Y1312165D03*
Y1302165D03*
Y1292165D03*
Y1332165D03*
Y1322165D03*
Y1362165D03*
Y1352165D03*
Y1342165D03*
Y1372165D03*
Y1410197D03*
Y1430197D03*
Y1420197D03*
Y1460197D03*
Y1450197D03*
Y1440197D03*
Y1480197D03*
Y1470197D03*
Y1500197D03*
Y1490197D03*
Y1530197D03*
Y1520197D03*
Y1510197D03*
Y1550197D03*
Y1540197D03*
Y1580197D03*
Y1570197D03*
Y1560197D03*
Y1600197D03*
Y1590197D03*
Y1620197D03*
Y1610197D03*
Y1650197D03*
Y1640197D03*
Y1630197D03*
Y1670197D03*
Y1660197D03*
Y1700197D03*
Y1690197D03*
Y1680197D03*
Y1720197D03*
Y1710197D03*
Y1768228D03*
Y1758228D03*
Y1798228D03*
Y1788228D03*
Y1778228D03*
Y1818228D03*
Y1808228D03*
Y1838228D03*
Y1828228D03*
Y1868228D03*
Y1858228D03*
Y1848228D03*
Y1888228D03*
Y1878228D03*
Y1918228D03*
Y1908228D03*
Y1898228D03*
Y1938228D03*
Y1928228D03*
Y1958228D03*
Y1948228D03*
Y1988228D03*
Y1978228D03*
Y1968228D03*
Y2008228D03*
Y1998228D03*
Y2038228D03*
Y2028228D03*
Y2018228D03*
Y2058228D03*
Y2048228D03*
Y2068228D03*
G54D17*
G01X67769Y1770835D02*
X71699D01*
G01D02*
X75376Y1774512D01*
X15547Y707364D03*
X25389D03*
X7673Y703427D03*
X15547Y715238D03*
Y723112D03*
Y730986D03*
X25389Y715238D03*
Y723112D03*
Y730986D03*
X7673Y711301D03*
Y719175D03*
Y727049D03*
X15547Y738860D03*
Y746734D03*
Y754608D03*
X25389Y738860D03*
Y746734D03*
Y754608D03*
X7673Y734923D03*
Y742797D03*
Y750671D03*
Y758545D03*
X15547Y762483D03*
Y770357D03*
Y778231D03*
X25389Y762483D03*
Y770357D03*
Y778231D03*
X7673Y766419D03*
Y774293D03*
Y782167D03*
X15547Y786105D03*
Y793979D03*
Y801853D03*
X25389Y786105D03*
Y793979D03*
Y801853D03*
X7673Y790041D03*
Y797915D03*
Y805790D03*
X15547Y809727D03*
Y817601D03*
Y825475D03*
X25389Y809727D03*
Y817601D03*
Y825475D03*
X7673Y813664D03*
Y821538D03*
Y829412D03*
X15547Y833349D03*
Y841223D03*
Y849097D03*
X25389Y833349D03*
Y841223D03*
Y849097D03*
X7673Y837286D03*
Y845160D03*
Y853034D03*
X15547Y856971D03*
Y864845D03*
Y872719D03*
X25389Y856971D03*
Y864845D03*
Y872719D03*
X7673Y860908D03*
Y868782D03*
Y876656D03*
X15547Y880593D03*
Y888467D03*
Y896341D03*
X25389Y880593D03*
Y888467D03*
Y896341D03*
X7673Y884530D03*
Y892404D03*
Y900278D03*
X15547Y904215D03*
Y912089D03*
Y919963D03*
X25389Y904215D03*
Y912089D03*
Y919963D03*
X7673Y908152D03*
Y916026D03*
Y923900D03*
X15547Y927837D03*
Y935711D03*
Y943585D03*
Y951459D03*
X25389Y927837D03*
Y935711D03*
Y943585D03*
Y951459D03*
X7673Y931774D03*
Y939648D03*
Y947522D03*
X15547Y959333D03*
Y967207D03*
Y975081D03*
X25389Y959333D03*
Y967207D03*
Y975081D03*
X7673Y955396D03*
Y963270D03*
Y971144D03*
Y979018D03*
Y994766D03*
X15547Y990829D03*
Y998703D03*
X25389Y990829D03*
Y998703D03*
X7673Y1002640D03*
Y1010514D03*
Y1018388D03*
X15547Y1006577D03*
Y1014451D03*
Y1022325D03*
X25389Y1006577D03*
Y1014451D03*
Y1022325D03*
X7673Y1026262D03*
X15547Y1030199D03*
X15551Y1065629D03*
X25393D03*
X7677Y1061692D03*
Y1069566D03*
X15551Y1073503D03*
Y1081377D03*
Y1089251D03*
X25393Y1073503D03*
Y1081377D03*
Y1089251D03*
X7677Y1077440D03*
Y1085314D03*
Y1093188D03*
X15551Y1097125D03*
Y1104999D03*
Y1112873D03*
Y1120748D03*
X25393Y1097125D03*
Y1104999D03*
Y1112873D03*
Y1120748D03*
X7677Y1101062D03*
Y1108936D03*
Y1116810D03*
X15551Y1128622D03*
Y1136496D03*
Y1144370D03*
X25393Y1128622D03*
Y1136496D03*
Y1144370D03*
X7677Y1124684D03*
Y1132558D03*
Y1140432D03*
X15551Y1152244D03*
Y1160118D03*
Y1167992D03*
X25393Y1152244D03*
Y1160118D03*
Y1167992D03*
X7677Y1148306D03*
Y1156180D03*
Y1164055D03*
X15551Y1175866D03*
Y1183740D03*
Y1191614D03*
X25393Y1175866D03*
Y1183740D03*
Y1191614D03*
X7677Y1171929D03*
Y1179803D03*
Y1187677D03*
X15551Y1199488D03*
Y1207362D03*
Y1215236D03*
X25393Y1199488D03*
Y1207362D03*
Y1215236D03*
X7677Y1195551D03*
Y1203425D03*
Y1211299D03*
X15551Y1223110D03*
Y1230984D03*
Y1238858D03*
X25393Y1223110D03*
Y1230984D03*
Y1238858D03*
X7677Y1219173D03*
Y1227047D03*
Y1234921D03*
X15551Y1246732D03*
Y1254606D03*
Y1262480D03*
X25393Y1246732D03*
Y1254606D03*
Y1262480D03*
X7677Y1242795D03*
Y1250669D03*
Y1258543D03*
X15551Y1270354D03*
Y1278228D03*
Y1286102D03*
X25393Y1270354D03*
Y1278228D03*
Y1286102D03*
X7677Y1266417D03*
Y1274291D03*
Y1282165D03*
X15551Y1293976D03*
Y1301850D03*
Y1309724D03*
X25393Y1293976D03*
Y1301850D03*
Y1309724D03*
X7677Y1290039D03*
Y1297913D03*
Y1305787D03*
Y1313661D03*
X15551Y1317598D03*
Y1325472D03*
Y1333346D03*
X25393Y1317598D03*
Y1325472D03*
Y1333346D03*
X7677Y1321535D03*
Y1329409D03*
Y1337283D03*
Y1353031D03*
Y1360905D03*
X15551Y1349094D03*
Y1356968D03*
X25393Y1349094D03*
Y1356968D03*
X7677Y1368779D03*
Y1376653D03*
Y1384527D03*
X15551Y1364842D03*
Y1372716D03*
Y1380590D03*
X25393Y1364842D03*
Y1372716D03*
Y1380590D03*
X15551Y1388464D03*
X33263Y703427D03*
Y711301D03*
Y719175D03*
Y727049D03*
Y734923D03*
Y742797D03*
Y750671D03*
Y758545D03*
Y766419D03*
Y774293D03*
Y782167D03*
Y790041D03*
Y797915D03*
Y805790D03*
Y813664D03*
Y821538D03*
Y829412D03*
Y837286D03*
Y845160D03*
Y853034D03*
Y860908D03*
Y868782D03*
Y876656D03*
Y884530D03*
Y892404D03*
Y900278D03*
Y908152D03*
Y916026D03*
Y923900D03*
Y931774D03*
Y939648D03*
Y947522D03*
Y955396D03*
Y963270D03*
Y971144D03*
Y979018D03*
Y994766D03*
Y1002640D03*
Y1010514D03*
Y1018388D03*
Y1026262D03*
X33267Y1061692D03*
Y1069566D03*
Y1077440D03*
Y1085314D03*
Y1093188D03*
Y1101062D03*
Y1108936D03*
Y1116810D03*
Y1124684D03*
Y1132558D03*
Y1140432D03*
Y1148306D03*
Y1156180D03*
Y1164055D03*
Y1171929D03*
Y1179803D03*
Y1187677D03*
Y1195551D03*
Y1203425D03*
Y1211299D03*
Y1219173D03*
Y1227047D03*
Y1234921D03*
Y1242795D03*
Y1250669D03*
Y1258543D03*
Y1266417D03*
Y1274291D03*
Y1282165D03*
Y1290039D03*
Y1297913D03*
Y1305787D03*
Y1313661D03*
Y1321535D03*
Y1329409D03*
Y1337283D03*
Y1353031D03*
Y1360905D03*
Y1368779D03*
Y1376653D03*
Y1384527D03*
G54D45*
G01X203542Y69353D02*
Y73105D01*
G01D02*
Y76857D01*
G01X199790Y73105D02*
X203542D01*
G01D02*
X207294D01*
G01X204069Y148298D02*
Y152050D01*
G01D02*
Y155802D01*
G01X200317Y152050D02*
X204069D01*
G01D02*
X207821D01*
G01X204137Y243816D02*
Y247568D01*
G01D02*
Y251320D01*
G01X200385Y247568D02*
X204137D01*
G01D02*
X207889D01*
G01X204597Y328034D02*
Y331786D01*
G01D02*
Y335538D01*
G01X200845Y331786D02*
X204597D01*
G01D02*
X208349D01*
G01X203541Y417980D02*
Y421732D01*
G01D02*
Y425484D01*
G01X199789Y421732D02*
X203541D01*
G01D02*
X207293D01*
G01X204333Y502765D02*
Y506517D01*
G01D02*
Y510269D01*
G01X200581Y506517D02*
X204333D01*
G01D02*
X208085D01*
G01X206668Y594378D02*
Y598130D01*
G01D02*
Y601882D01*
G01X202916Y598130D02*
X206668D01*
G01D02*
X210420D01*
G01X204596Y677893D02*
Y681645D01*
G01D02*
Y685397D01*
G01X200844Y681645D02*
X204596D01*
G01D02*
X208348D01*
G01X205626Y770774D02*
Y774526D01*
G01D02*
Y778278D01*
G01X201874Y774526D02*
X205626D01*
G01D02*
X209378D01*
G01X205386Y852492D02*
Y856244D01*
G01D02*
Y859996D01*
G01X201634Y856244D02*
X205386D01*
G01D02*
X209138D01*
G01X210091Y943450D02*
Y947202D01*
G01D02*
Y950954D01*
G01X206339Y947202D02*
X210091D01*
G01D02*
X213843D01*
G01X209296Y1028792D02*
Y1032544D01*
G01D02*
Y1036296D01*
G01X205544Y1032544D02*
X209296D01*
G01D02*
X213048D01*
G01X205030Y1119104D02*
Y1122856D01*
G01D02*
Y1126608D01*
G01X201278Y1122856D02*
X205030D01*
G01D02*
X208782D01*
G01X205122Y1202481D02*
Y1206233D01*
G01D02*
Y1209985D01*
G01X201370Y1206233D02*
X205122D01*
G01D02*
X208874D01*
G01X205626Y1295352D02*
Y1299104D01*
G01D02*
Y1302856D01*
G01X201874Y1299104D02*
X205626D01*
G01D02*
X209378D01*
G01X204332Y1377214D02*
Y1380966D01*
G01D02*
Y1384718D01*
G01X200580Y1380966D02*
X204332D01*
G01D02*
X208084D01*
G01X203243Y1470410D02*
Y1474162D01*
G01D02*
Y1477914D01*
G01X199491Y1474162D02*
X203243D01*
G01D02*
X206995D01*
G01X204859Y1553525D02*
Y1557277D01*
G01D02*
Y1561029D01*
G01X201107Y1557277D02*
X204859D01*
G01D02*
X208611D01*
G01X205923Y1644425D02*
Y1648177D01*
G01D02*
Y1651929D01*
G01X202171Y1648177D02*
X205923D01*
G01D02*
X209675D01*
G01X205387Y1727599D02*
Y1731351D01*
G01D02*
Y1735103D01*
G01X201635Y1731351D02*
X205387D01*
G01D02*
X209139D01*
G01X205310Y1819475D02*
Y1823227D01*
G01D02*
Y1826979D01*
G01X201558Y1823227D02*
X205310D01*
G01D02*
X209062D01*
G01X204069Y1896668D02*
Y1900420D01*
G01D02*
Y1904172D01*
G01X200317Y1900420D02*
X204069D01*
G01D02*
X207821D01*
G01X205905Y1994978D02*
Y1998730D01*
G01D02*
Y2002482D01*
G01X202153Y1998730D02*
X205905D01*
G01D02*
X209657D01*
G01X205310Y2039636D02*
Y2043388D01*
G01D02*
Y2047140D01*
G01X201558Y2043388D02*
X205310D01*
G01D02*
X209062D01*
G54D27*
X65354Y114960D03*
Y464960D03*
Y814960D03*
Y1164960D03*
Y1514960D03*
Y1864960D03*
X307086Y127165D03*
Y477165D03*
Y827165D03*
Y1343504D03*
Y1693504D03*
X307087Y2043503D03*
G54D36*
X119920Y328071D03*
Y676102D03*
Y1024134D03*
Y1372165D03*
Y1720197D03*
Y2068228D03*
G54D18*
X20468Y696341D03*
Y984333D03*
X20472Y1054606D03*
Y1342598D03*
G54D46*
G01X54413Y1253378D02*
X57458D01*
G01X54543Y1299531D02*
Y1296513D01*
G01X63061Y1299596D02*
Y1296312D01*
G01X67568Y1299431D02*
Y1296654D01*
G01X92860Y698443D02*
X94487D01*
X96308Y696622D01*
G01X101189Y1081791D02*
X96684D01*
G01X100293Y1447919D02*
X97465D01*
G01X105845Y20080D02*
Y22090D01*
X106335Y22580D01*
G01X105845Y15847D02*
Y20080D01*
G01X108082Y41803D02*
Y38899D01*
G01X104940Y46285D02*
Y47167D01*
X102646Y49461D01*
G01X102727Y58250D02*
Y60670D01*
X104350Y62293D01*
G01X107268Y81355D02*
Y84746D01*
X108672Y86150D01*
G01X104518Y426104D02*
X101990D01*
G01X109475Y434743D02*
X107668Y432936D01*
Y429254D01*
G01X111017Y419566D02*
X107668Y422915D01*
Y422954D01*
G01X113018Y706356D02*
X115614Y703760D01*
X142860D01*
X149867Y710767D01*
Y733748D01*
X169337Y753218D01*
Y769222D01*
X165095Y773464D01*
Y785533D01*
X159244Y791384D01*
X151052D01*
X148565Y788897D01*
X135546D01*
X130783Y784134D01*
X119920D01*
G01X101196Y745139D02*
X98124D01*
G01X104442Y774100D02*
X101244D01*
G01X111967Y795261D02*
Y792563D01*
X107615Y788211D01*
Y777299D01*
G01X107617Y771001D02*
X110957D01*
X112836Y769122D01*
G01X115139Y849240D02*
X114692Y848793D01*
Y789362D01*
X119920Y784134D01*
G01X101189Y1081791D02*
Y1076901D01*
G01X101282Y1096403D02*
X98652D01*
G01X108819Y1119015D02*
X109348D01*
X112503Y1115860D01*
G01X108468Y1129286D02*
X108816Y1128938D01*
Y1125313D01*
G01X108573Y1473357D02*
Y1484626D01*
X113518Y1489571D01*
G01X108574Y1467057D02*
Y1463389D01*
G01X101780Y1789947D02*
X99294D01*
G01X119920Y1818228D02*
X108819D01*
G01X105669D02*
Y1815227D01*
G01X108819Y1815078D02*
Y1812118D01*
G01Y1821378D02*
Y1824470D01*
G01X139920Y436102D02*
X155331D01*
X155348Y436119D01*
G01X158559Y88108D02*
X161339D01*
G01X155370Y91281D02*
X159417D01*
G01X155366Y85017D02*
X158901D01*
G01X158498Y436119D02*
X161517D01*
G01X155351Y439268D02*
X159019D01*
G01X155348Y432969D02*
X158807D01*
G01X155356Y780982D02*
X158956D01*
G01X158519Y784141D02*
X161479D01*
G01X159053Y787280D02*
X155362D01*
G01X155264Y1135344D02*
X156071Y1136151D01*
X159382D01*
G01X155263Y1129045D02*
X158456D01*
G01X155816Y1477124D02*
X159216D01*
G01X155834Y1483424D02*
X159526Y1483434D01*
G01X158806Y1828225D02*
X161844D01*
G01X155570Y1831380D02*
X159822D01*
G01X155561Y1825087D02*
X159075D01*
G01X175989Y944537D02*
X176947Y943579D01*
X181134D01*
G01X176011Y936829D02*
X177161Y937979D01*
X181223D01*
G01X175359Y963486D02*
X176174Y962671D01*
X181046D01*
G01X175561Y955964D02*
X176668Y957071D01*
X181135D01*
G01X175135Y972490D02*
X176199Y973554D01*
X181389D01*
G01X175022Y980281D02*
X176149Y979154D01*
X181482D01*
G01X175742Y989958D02*
X176742Y990958D01*
X181247D01*
G01X175449Y997660D02*
Y997636D01*
X176527Y996558D01*
X181203D01*
G01X175698Y1008730D02*
X176681Y1009713D01*
X180965D01*
G01X180968Y1015313D02*
X176456D01*
X175473Y1016296D01*
G01X179177Y1030622D02*
X176592D01*
X175448Y1031766D01*
G01X179179Y1025022D02*
X176922D01*
X175897Y1023997D01*
G01X264929Y115559D02*
X267627D01*
G01X261535Y128228D02*
X261487Y128276D01*
X256947D01*
G01X261779Y115559D02*
X257125D01*
G01X265722Y463102D02*
X268958D01*
X268961Y463099D01*
G01X265737Y473680D02*
X268885D01*
X268888Y473677D01*
G01X264335Y812170D02*
X270048D01*
X270070Y812192D01*
G01X255837Y823626D02*
X261003D01*
X261025Y823604D01*
G01X255687Y812192D02*
X261163D01*
X261185Y812170D01*
G01X272111Y463099D02*
X274991D01*
G01X288712Y1864565D02*
X292614D01*
G01X285644Y1858668D02*
X280240D01*
G01X285562Y1864565D02*
X279976D01*
G01X317058Y1162266D02*
X312527D01*
G01X317114Y1172804D02*
X312698D01*
G01X305756Y1524401D02*
X302267D01*
G01X305486Y1513883D02*
X301734D01*
G01X320264Y1172804D02*
X323403D01*
G54D37*
X163385Y27205D03*
Y202205D03*
Y377205D03*
X163386Y552205D03*
Y727205D03*
X163385Y902205D03*
Y1077205D03*
Y1252205D03*
Y1427205D03*
Y1602205D03*
Y1777205D03*
Y1952205D03*
X373385Y32520D03*
Y207520D03*
Y382520D03*
X373386Y557520D03*
Y732520D03*
X373385Y907520D03*
Y1082520D03*
Y1257520D03*
Y1432520D03*
Y1607520D03*
Y1782520D03*
Y1957520D03*
G54D28*
X55254Y554500D03*
Y1612504D03*
G54D19*
X25389Y1030199D03*
X25393Y1388464D03*
G54D47*
G01X-723776Y2987387D02*
Y-376795D01*
Y-489221D01*
X1782976D01*
Y-376795D01*
Y2987387D01*
X-723776D01*
G01X-4000Y-62500D02*
Y-137500D01*
X496000D01*
Y-62500D01*
X-4000D01*
G01X8000Y-127500D02*
Y-132500D01*
G01X6543Y-127500D02*
X9457D01*
G01X14367Y-132500D02*
X11833D01*
Y-127500D01*
X14367D01*
G01X13353Y-129917D02*
X11833D01*
G01X16933Y-127500D02*
Y-132500D01*
X19467D01*
G01X23300Y-132667D02*
X23173Y-132583D01*
Y-132417D01*
X23300Y-132333D01*
X23427Y-132417D01*
Y-132583D01*
X23300Y-132667D01*
G01Y-130417D02*
X23173Y-130333D01*
Y-130167D01*
X23300Y-130083D01*
X23427Y-130167D01*
Y-130333D01*
X23300Y-130417D01*
G01X28083Y-134167D02*
X27450Y-133333D01*
X27133Y-132500D01*
Y-129167D01*
X27450Y-128333D01*
X28083Y-127500D01*
G01X33500D02*
X32993Y-127667D01*
X32613Y-128083D01*
X32360Y-128583D01*
X32170Y-129250D01*
X32107Y-130000D01*
X32170Y-130750D01*
X32360Y-131417D01*
X32613Y-131917D01*
X32993Y-132333D01*
X33500Y-132500D01*
X34007Y-132333D01*
X34387Y-131917D01*
X34640Y-131417D01*
X34830Y-130750D01*
X34893Y-130000D01*
X34830Y-129250D01*
X34640Y-128583D01*
X34387Y-128083D01*
X34007Y-127667D01*
X33500Y-127500D01*
G01X37207Y-131500D02*
X37587Y-132083D01*
X38093Y-132417D01*
X38663Y-132500D01*
X39170Y-132417D01*
X39677Y-132000D01*
X39993Y-131500D01*
X40057Y-131000D01*
X39930Y-130417D01*
X39487Y-130000D01*
X39043Y-129833D01*
X38473D01*
G01X39043D02*
X39423Y-129583D01*
X39740Y-129167D01*
X39867Y-128667D01*
X39740Y-128167D01*
X39423Y-127750D01*
X38853Y-127500D01*
X38283Y-127583D01*
X37713Y-127917D01*
G01X44017Y-134167D02*
X44650Y-133333D01*
X44967Y-132500D01*
Y-129167D01*
X44650Y-128333D01*
X44017Y-127500D01*
G01X47407Y-131500D02*
X47787Y-132083D01*
X48293Y-132417D01*
X48863Y-132500D01*
X49370Y-132417D01*
X49877Y-132000D01*
X50193Y-131500D01*
X50257Y-131000D01*
X50130Y-130417D01*
X49687Y-130000D01*
X49243Y-129833D01*
X48673D01*
G01X49243D02*
X49623Y-129583D01*
X49940Y-129167D01*
X50067Y-128667D01*
X49940Y-128167D01*
X49623Y-127750D01*
X49053Y-127500D01*
X48483Y-127583D01*
X47913Y-127917D01*
G01X52697Y-128333D02*
X53077Y-127833D01*
X53520Y-127583D01*
X54027Y-127500D01*
X54660Y-127667D01*
X55103Y-128083D01*
X55230Y-128583D01*
X55167Y-129083D01*
X54913Y-129500D01*
X53647Y-130333D01*
X53077Y-130917D01*
X52697Y-131750D01*
X52570Y-132500D01*
X55230D01*
G01X58873D02*
X59000Y-131417D01*
X59190Y-130500D01*
X59443Y-129667D01*
X59760Y-128750D01*
X60267Y-127500D01*
X57733D01*
G01X63277Y-130833D02*
X64923D01*
G01X67997Y-128333D02*
X68377Y-127833D01*
X68820Y-127583D01*
X69327Y-127500D01*
X69960Y-127667D01*
X70403Y-128083D01*
X70530Y-128583D01*
X70467Y-129083D01*
X70213Y-129500D01*
X68947Y-130333D01*
X68377Y-130917D01*
X67997Y-131750D01*
X67870Y-132500D01*
X70530D01*
G01X72907Y-131500D02*
X73287Y-132083D01*
X73793Y-132417D01*
X74363Y-132500D01*
X74870Y-132417D01*
X75377Y-132000D01*
X75693Y-131500D01*
X75757Y-131000D01*
X75630Y-130417D01*
X75187Y-130000D01*
X74743Y-129833D01*
X74173D01*
G01X74743D02*
X75123Y-129583D01*
X75440Y-129167D01*
X75567Y-128667D01*
X75440Y-128167D01*
X75123Y-127750D01*
X74553Y-127500D01*
X73983Y-127583D01*
X73413Y-127917D01*
G01X80160Y-132500D02*
Y-127500D01*
X77817Y-131083D01*
X80983D01*
G01X83107Y-131750D02*
X83487Y-132167D01*
X83930Y-132417D01*
X84500Y-132500D01*
X85070Y-132333D01*
X85513Y-132000D01*
X85830Y-131417D01*
X85893Y-130750D01*
X85767Y-130083D01*
X85450Y-129667D01*
X85007Y-129333D01*
X84563Y-129250D01*
X84120Y-129333D01*
X83550Y-129667D01*
X83740Y-127500D01*
X85450D01*
G01X93497Y-132500D02*
Y-127500D01*
X95903D01*
G01X95017Y-129917D02*
X93497D01*
G01X98217Y-132500D02*
X99800Y-127500D01*
X101383Y-132500D01*
G01X100813Y-130750D02*
X98787D01*
G01X103570Y-132500D02*
X106230Y-127500D01*
G01X103570D02*
X106230Y-132500D01*
G01X110000Y-132667D02*
X109873Y-132583D01*
Y-132417D01*
X110000Y-132333D01*
X110127Y-132417D01*
Y-132583D01*
X110000Y-132667D01*
G01Y-130417D02*
X109873Y-130333D01*
Y-130167D01*
X110000Y-130083D01*
X110127Y-130167D01*
Y-130333D01*
X110000Y-130417D01*
G01X114783Y-134167D02*
X114150Y-133333D01*
X113833Y-132500D01*
Y-129167D01*
X114150Y-128333D01*
X114783Y-127500D01*
G01X120200D02*
X119693Y-127667D01*
X119313Y-128083D01*
X119060Y-128583D01*
X118870Y-129250D01*
X118807Y-130000D01*
X118870Y-130750D01*
X119060Y-131417D01*
X119313Y-131917D01*
X119693Y-132333D01*
X120200Y-132500D01*
X120707Y-132333D01*
X121087Y-131917D01*
X121340Y-131417D01*
X121530Y-130750D01*
X121593Y-130000D01*
X121530Y-129250D01*
X121340Y-128583D01*
X121087Y-128083D01*
X120707Y-127667D01*
X120200Y-127500D01*
G01X123907Y-131500D02*
X124287Y-132083D01*
X124793Y-132417D01*
X125363Y-132500D01*
X125870Y-132417D01*
X126377Y-132000D01*
X126693Y-131500D01*
X126757Y-131000D01*
X126630Y-130417D01*
X126187Y-130000D01*
X125743Y-129833D01*
X125173D01*
G01X125743D02*
X126123Y-129583D01*
X126440Y-129167D01*
X126567Y-128667D01*
X126440Y-128167D01*
X126123Y-127750D01*
X125553Y-127500D01*
X124983Y-127583D01*
X124413Y-127917D01*
G01X130717Y-134167D02*
X131350Y-133333D01*
X131667Y-132500D01*
Y-129167D01*
X131350Y-128333D01*
X130717Y-127500D01*
G01X134107Y-131500D02*
X134487Y-132083D01*
X134993Y-132417D01*
X135563Y-132500D01*
X136070Y-132417D01*
X136577Y-132000D01*
X136893Y-131500D01*
X136957Y-131000D01*
X136830Y-130417D01*
X136387Y-130000D01*
X135943Y-129833D01*
X135373D01*
G01X135943D02*
X136323Y-129583D01*
X136640Y-129167D01*
X136767Y-128667D01*
X136640Y-128167D01*
X136323Y-127750D01*
X135753Y-127500D01*
X135183Y-127583D01*
X134613Y-127917D01*
G01X139523Y-131917D02*
X139967Y-132333D01*
X140473Y-132500D01*
X140980Y-132333D01*
X141423Y-131833D01*
X141740Y-131083D01*
X141867Y-130333D01*
Y-129417D01*
X141740Y-128667D01*
X141423Y-128000D01*
X141043Y-127667D01*
X140600Y-127500D01*
X140093Y-127667D01*
X139713Y-128000D01*
X139460Y-128500D01*
X139333Y-129167D01*
X139460Y-129750D01*
X139777Y-130333D01*
X140157Y-130667D01*
X140600Y-130750D01*
X141107Y-130583D01*
X141487Y-130167D01*
X141867Y-129417D01*
G01X145573Y-132500D02*
X145700Y-131417D01*
X145890Y-130500D01*
X146143Y-129667D01*
X146460Y-128750D01*
X146967Y-127500D01*
X144433D01*
G01X149977Y-130833D02*
X151623D01*
G01X154507Y-131500D02*
X154887Y-132083D01*
X155393Y-132417D01*
X155963Y-132500D01*
X156470Y-132417D01*
X156977Y-132000D01*
X157293Y-131500D01*
X157357Y-131000D01*
X157230Y-130417D01*
X156787Y-130000D01*
X156343Y-129833D01*
X155773D01*
G01X156343D02*
X156723Y-129583D01*
X157040Y-129167D01*
X157167Y-128667D01*
X157040Y-128167D01*
X156723Y-127750D01*
X156153Y-127500D01*
X155583Y-127583D01*
X155013Y-127917D01*
G01X159797Y-130417D02*
X160240Y-129833D01*
X160620Y-129500D01*
X161127Y-129333D01*
X161570Y-129500D01*
X161887Y-129833D01*
X162140Y-130333D01*
X162203Y-130917D01*
X162140Y-131417D01*
X161887Y-131917D01*
X161507Y-132333D01*
X161063Y-132500D01*
X160557Y-132333D01*
X160113Y-131833D01*
X159860Y-131083D01*
X159797Y-130250D01*
X159923Y-129167D01*
X160113Y-128583D01*
X160430Y-128000D01*
X160873Y-127583D01*
X161317Y-127500D01*
X161760Y-127667D01*
X162077Y-128083D01*
G01X166100Y-132500D02*
Y-127500D01*
X165340Y-128500D01*
G01Y-132500D02*
X166860D01*
G01X171960D02*
Y-127500D01*
X169617Y-131083D01*
X172783D01*
G01X191000Y-62500D02*
Y-137500D01*
G01Y-112500D02*
X294000D01*
Y-87500D01*
G01X191000D02*
X294000D01*
G01X301507Y-122500D02*
Y-117500D01*
X302773D01*
X303280Y-117750D01*
X303660Y-118083D01*
X303977Y-118583D01*
X304230Y-119167D01*
X304293Y-120000D01*
X304230Y-120833D01*
X303977Y-121417D01*
X303660Y-121917D01*
X303280Y-122250D01*
X302773Y-122500D01*
X301507D01*
G01X306417D02*
X308000Y-117500D01*
X309583Y-122500D01*
G01X309013Y-120750D02*
X306987D01*
G01X313100Y-117500D02*
Y-122500D01*
G01X311643Y-117500D02*
X314557D01*
G01X319467Y-122500D02*
X316933D01*
Y-117500D01*
X319467D01*
G01X318453Y-119917D02*
X316933D01*
G01X323300Y-122667D02*
X323173Y-122583D01*
Y-122417D01*
X323300Y-122333D01*
X323427Y-122417D01*
Y-122583D01*
X323300Y-122667D01*
G01Y-120417D02*
X323173Y-120333D01*
Y-120167D01*
X323300Y-120083D01*
X323427Y-120167D01*
Y-120333D01*
X323300Y-120417D01*
G01X296000Y-62500D02*
Y-137500D01*
G01X294000Y-62500D02*
Y-137500D01*
G01X301633Y-97500D02*
Y-92500D01*
X303153D01*
X303660Y-92750D01*
X304040Y-93333D01*
X304167Y-94000D01*
X304040Y-94667D01*
X303723Y-95167D01*
X303153Y-95417D01*
X301633D01*
G01X306860Y-97667D02*
X309140Y-92500D01*
G01X311643Y-97500D02*
Y-92500D01*
X314557Y-97500D01*
Y-92500D01*
G01X318200Y-97667D02*
X318073Y-97583D01*
Y-97417D01*
X318200Y-97333D01*
X318327Y-97417D01*
Y-97583D01*
X318200Y-97667D01*
G01Y-95417D02*
X318073Y-95333D01*
Y-95167D01*
X318200Y-95083D01*
X318327Y-95167D01*
Y-95333D01*
X318200Y-95417D01*
G01X296000Y-112500D02*
X496000D01*
G01X301633Y-72500D02*
Y-67500D01*
X303153D01*
X303660Y-67750D01*
X304040Y-68333D01*
X304167Y-69000D01*
X304040Y-69667D01*
X303723Y-70167D01*
X303153Y-70417D01*
X301633D01*
G01X306733Y-72500D02*
Y-67500D01*
X308317D01*
X308823Y-67750D01*
X309140Y-68083D01*
X309267Y-68750D01*
X309140Y-69417D01*
X308760Y-69833D01*
X308317Y-70083D01*
X306733D01*
G01X308317D02*
X309267Y-72500D01*
G01X313100D02*
X312593Y-72417D01*
X312150Y-72083D01*
X311770Y-71583D01*
X311517Y-71000D01*
X311390Y-70333D01*
Y-69667D01*
X311517Y-69000D01*
X311770Y-68417D01*
X312150Y-67917D01*
X312593Y-67583D01*
X313100Y-67500D01*
X313607Y-67583D01*
X314050Y-67917D01*
X314430Y-68417D01*
X314683Y-69000D01*
X314810Y-69667D01*
Y-70333D01*
X314683Y-71000D01*
X314430Y-71583D01*
X314050Y-72083D01*
X313607Y-72417D01*
X313100Y-72500D01*
G01X316933Y-71500D02*
X317250Y-72000D01*
X317630Y-72333D01*
X318073Y-72500D01*
X318580Y-72333D01*
X318960Y-72000D01*
X319340Y-71500D01*
X319467Y-70833D01*
Y-67500D01*
G01X324567Y-72500D02*
X322033D01*
Y-67500D01*
X324567D01*
G01X323553Y-69917D02*
X322033D01*
G01X329793Y-67917D02*
X329413Y-67667D01*
X328970Y-67500D01*
X328463D01*
X327893Y-67750D01*
X327450Y-68167D01*
X327133Y-68667D01*
X326880Y-69500D01*
X326817Y-70250D01*
X326943Y-71000D01*
X327133Y-71500D01*
X327513Y-72000D01*
X327957Y-72333D01*
X328400Y-72500D01*
X328843D01*
X329287Y-72333D01*
X329667Y-72083D01*
X329983Y-71750D01*
G01X333500Y-67500D02*
Y-72500D01*
G01X332043Y-67500D02*
X334957D01*
G01X338600Y-72667D02*
X338473Y-72583D01*
Y-72417D01*
X338600Y-72333D01*
X338727Y-72417D01*
Y-72583D01*
X338600Y-72667D01*
G01Y-70417D02*
X338473Y-70333D01*
Y-70167D01*
X338600Y-70083D01*
X338727Y-70167D01*
Y-70333D01*
X338600Y-70417D01*
G01X296000Y-87500D02*
X496000D01*
G01X411000Y-112500D02*
Y-137500D01*
G01X416633Y-122500D02*
Y-117500D01*
X418217D01*
X418723Y-117750D01*
X419040Y-118083D01*
X419167Y-118750D01*
X419040Y-119417D01*
X418660Y-119833D01*
X418217Y-120083D01*
X416633D01*
G01X418217D02*
X419167Y-122500D01*
G01X424267D02*
X421733D01*
Y-117500D01*
X424267D01*
G01X423253Y-119917D02*
X421733D01*
G01X426517Y-117500D02*
X428100Y-122500D01*
X429683Y-117500D01*
G01X433200Y-122667D02*
X433073Y-122583D01*
Y-122417D01*
X433200Y-122333D01*
X433327Y-122417D01*
Y-122583D01*
X433200Y-122667D01*
G01Y-120417D02*
X433073Y-120333D01*
Y-120167D01*
X433200Y-120083D01*
X433327Y-120167D01*
Y-120333D01*
X433200Y-120417D01*
G01X460000Y-112500D02*
Y-137500D01*
G01X-723776Y2987387D02*
Y-376795D01*
Y-489221D01*
X1782976D01*
Y-376795D01*
Y2987387D01*
X-723776D01*
G01X6705Y-124160D02*
X7332Y-124685D01*
X8037Y-125000D01*
X8663D01*
X9290Y-124685D01*
X9760Y-124160D01*
X9995Y-123425D01*
X9838Y-122690D01*
X9447Y-122060D01*
X8742Y-121640D01*
X7802Y-121430D01*
X7253Y-121010D01*
X7018Y-120275D01*
X7175Y-119540D01*
X7567Y-119015D01*
X8115Y-118700D01*
X8663D01*
X9212Y-118910D01*
X9682Y-119435D01*
G01X13005Y-125000D02*
Y-118700D01*
G01X16295D02*
Y-125000D01*
G01Y-121850D02*
X13005D01*
G01X20010Y-118700D02*
X21890D01*
G01X20950D02*
Y-125000D01*
G01X20010D02*
X21890D01*
G01X28817D02*
X25683D01*
Y-118700D01*
X28817D01*
G01X27563Y-121745D02*
X25683D01*
G01X31748Y-125000D02*
Y-118700D01*
X35352Y-125000D01*
Y-118700D01*
G01X39693Y-126155D02*
X40007Y-124790D01*
G01X46150Y-118700D02*
Y-125000D01*
G01X44348Y-118700D02*
X47952D01*
G01X50492Y-125000D02*
X52450Y-118700D01*
X54408Y-125000D01*
G01X53703Y-122795D02*
X51197D01*
G01X57810Y-118700D02*
X59690D01*
G01X58750D02*
Y-125000D01*
G01X57810D02*
X59690D01*
G01X62700Y-118700D02*
X63797Y-125000D01*
X65050Y-118700D01*
X66303Y-125000D01*
X67400Y-118700D01*
G01X69392Y-125000D02*
X71350Y-118700D01*
X73308Y-125000D01*
G01X72603Y-122795D02*
X70097D01*
G01X75848Y-125000D02*
Y-118700D01*
X79452Y-125000D01*
Y-118700D01*
G01X88683Y-125000D02*
Y-118700D01*
X90642D01*
X91268Y-119015D01*
X91660Y-119435D01*
X91817Y-120275D01*
X91660Y-121115D01*
X91190Y-121640D01*
X90642Y-121955D01*
X88683D01*
G01X90642D02*
X91817Y-125000D01*
G01X96550Y-125210D02*
X96393Y-125105D01*
Y-124895D01*
X96550Y-124790D01*
X96707Y-124895D01*
Y-125105D01*
X96550Y-125210D01*
G01X102850Y-125000D02*
X102223Y-124895D01*
X101675Y-124475D01*
X101205Y-123845D01*
X100892Y-123110D01*
X100735Y-122270D01*
Y-121430D01*
X100892Y-120590D01*
X101205Y-119855D01*
X101675Y-119225D01*
X102223Y-118805D01*
X102850Y-118700D01*
X103477Y-118805D01*
X104025Y-119225D01*
X104495Y-119855D01*
X104808Y-120590D01*
X104965Y-121430D01*
Y-122270D01*
X104808Y-123110D01*
X104495Y-123845D01*
X104025Y-124475D01*
X103477Y-124895D01*
X102850Y-125000D01*
G01X109150Y-125210D02*
X108993Y-125105D01*
Y-124895D01*
X109150Y-124790D01*
X109307Y-124895D01*
Y-125105D01*
X109150Y-125210D01*
G01X117173Y-119225D02*
X116703Y-118910D01*
X116155Y-118700D01*
X115528D01*
X114823Y-119015D01*
X114275Y-119540D01*
X113883Y-120170D01*
X113570Y-121220D01*
X113492Y-122165D01*
X113648Y-123110D01*
X113883Y-123740D01*
X114353Y-124370D01*
X114902Y-124790D01*
X115450Y-125000D01*
X115998D01*
X116547Y-124790D01*
X117017Y-124475D01*
X117408Y-124055D01*
G01X121750Y-125210D02*
X121593Y-125105D01*
Y-124895D01*
X121750Y-124790D01*
X121907Y-124895D01*
Y-125105D01*
X121750Y-125210D01*
G01X6627Y-115000D02*
Y-108700D01*
G01X9603D02*
X6627Y-112585D01*
G01X10073Y-115000D02*
X7958Y-110800D01*
G01X12927Y-108700D02*
Y-113215D01*
X13240Y-114160D01*
X13867Y-114790D01*
X14650Y-115000D01*
X15433Y-114790D01*
X16060Y-114160D01*
X16373Y-113215D01*
Y-108700D01*
G01X22517Y-115000D02*
X19383D01*
Y-108700D01*
X22517D01*
G01X21263Y-111745D02*
X19383D01*
G01X26310Y-108700D02*
X28190D01*
G01X27250D02*
Y-115000D01*
G01X26310D02*
X28190D01*
G01X38205Y-114160D02*
X38832Y-114685D01*
X39537Y-115000D01*
X40163D01*
X40790Y-114685D01*
X41260Y-114160D01*
X41495Y-113425D01*
X41338Y-112690D01*
X40947Y-112060D01*
X40242Y-111640D01*
X39302Y-111430D01*
X38753Y-111010D01*
X38518Y-110275D01*
X38675Y-109540D01*
X39067Y-109015D01*
X39615Y-108700D01*
X40163D01*
X40712Y-108910D01*
X41182Y-109435D01*
G01X44505Y-115000D02*
Y-108700D01*
G01X47795D02*
Y-115000D01*
G01Y-111850D02*
X44505D01*
G01X50492Y-115000D02*
X52450Y-108700D01*
X54408Y-115000D01*
G01X53703Y-112795D02*
X51197D01*
G01X56948Y-115000D02*
Y-108700D01*
X60552Y-115000D01*
Y-108700D01*
G01X69705Y-115000D02*
Y-108700D01*
G01X72995D02*
Y-115000D01*
G01Y-111850D02*
X69705D01*
G01X76005Y-114160D02*
X76632Y-114685D01*
X77337Y-115000D01*
X77963D01*
X78590Y-114685D01*
X79060Y-114160D01*
X79295Y-113425D01*
X79138Y-112690D01*
X78747Y-112060D01*
X78042Y-111640D01*
X77102Y-111430D01*
X76553Y-111010D01*
X76318Y-110275D01*
X76475Y-109540D01*
X76867Y-109015D01*
X77415Y-108700D01*
X77963D01*
X78512Y-108910D01*
X78982Y-109435D01*
G01X83010Y-108700D02*
X84890D01*
G01X83950D02*
Y-115000D01*
G01X83010D02*
X84890D01*
G01X88292D02*
X90250Y-108700D01*
X92208Y-115000D01*
G01X91503Y-112795D02*
X88997D01*
G01X94748Y-115000D02*
Y-108700D01*
X98352Y-115000D01*
Y-108700D01*
G01X103320Y-111850D02*
X104887D01*
Y-113740D01*
X104417Y-114370D01*
X103868Y-114790D01*
X103085Y-115000D01*
X102302Y-114790D01*
X101753Y-114370D01*
X101283Y-113740D01*
X100970Y-113005D01*
X100813Y-112165D01*
Y-111430D01*
X100970Y-110800D01*
X101283Y-110065D01*
X101753Y-109435D01*
X102223Y-109015D01*
X102850Y-108700D01*
X103398D01*
X104025Y-108910D01*
X104495Y-109330D01*
G01X108993Y-116155D02*
X109307Y-114790D01*
G01X115450Y-108700D02*
Y-115000D01*
G01X113648Y-108700D02*
X117252D01*
G01X119792Y-115000D02*
X121750Y-108700D01*
X123708Y-115000D01*
G01X123003Y-112795D02*
X120497D01*
G01X128050Y-115000D02*
X127423Y-114895D01*
X126875Y-114475D01*
X126405Y-113845D01*
X126092Y-113110D01*
X125935Y-112270D01*
Y-111430D01*
X126092Y-110590D01*
X126405Y-109855D01*
X126875Y-109225D01*
X127423Y-108805D01*
X128050Y-108700D01*
X128677Y-108805D01*
X129225Y-109225D01*
X129695Y-109855D01*
X130008Y-110590D01*
X130165Y-111430D01*
Y-112270D01*
X130008Y-113110D01*
X129695Y-113845D01*
X129225Y-114475D01*
X128677Y-114895D01*
X128050Y-115000D01*
G01X140650D02*
Y-112165D01*
X139083Y-108700D01*
G01X142217D02*
X140650Y-112165D01*
G01X145227Y-108700D02*
Y-113215D01*
X145540Y-114160D01*
X146167Y-114790D01*
X146950Y-115000D01*
X147733Y-114790D01*
X148360Y-114160D01*
X148673Y-113215D01*
Y-108700D01*
G01X151292Y-115000D02*
X153250Y-108700D01*
X155208Y-115000D01*
G01X154503Y-112795D02*
X151997D01*
G01X157748Y-115000D02*
Y-108700D01*
X161352Y-115000D01*
Y-108700D01*
G01X30650Y-92300D02*
X28130Y-91883D01*
X25925Y-90217D01*
X24035Y-87717D01*
X22775Y-84800D01*
X22145Y-81467D01*
Y-78133D01*
X22775Y-74800D01*
X24035Y-71883D01*
X25925Y-69384D01*
X28130Y-67717D01*
X30650Y-67300D01*
X33170Y-67717D01*
X35375Y-69384D01*
X37265Y-71883D01*
X38525Y-74800D01*
X39155Y-78133D01*
Y-81467D01*
X38525Y-84800D01*
X37265Y-87717D01*
X35375Y-90217D01*
X33170Y-91883D01*
X30650Y-92300D01*
G01X33170Y-85633D02*
X36950Y-92300D01*
G01X50495Y-75634D02*
Y-87300D01*
X51755Y-90217D01*
X53645Y-91883D01*
X55850Y-92300D01*
X58055Y-91883D01*
X59945Y-90217D01*
X61205Y-87300D01*
G01Y-92300D02*
Y-75634D01*
G01X86720Y-92300D02*
Y-75634D01*
G01Y-78550D02*
X85460Y-76884D01*
X83570Y-76050D01*
X81365Y-75634D01*
X79160Y-76467D01*
X77270Y-78133D01*
X76010Y-80634D01*
X75380Y-83967D01*
X76010Y-87300D01*
X77270Y-89801D01*
X79160Y-91467D01*
X81365Y-92300D01*
X83570Y-91883D01*
X85460Y-90634D01*
X86720Y-88967D01*
G01X100895Y-92300D02*
Y-75634D01*
G01Y-79800D02*
X102155Y-77717D01*
X104045Y-76050D01*
X106565Y-75634D01*
X108770Y-76050D01*
X110660Y-77717D01*
X111605Y-80634D01*
Y-92300D01*
G01X131450Y-67300D02*
Y-92300D01*
G01X127040Y-75634D02*
X135860D01*
G01X162320Y-92300D02*
Y-75634D01*
G01Y-78550D02*
X161060Y-76884D01*
X159170Y-76050D01*
X156965Y-75634D01*
X154760Y-76467D01*
X152870Y-78133D01*
X151610Y-80634D01*
X150980Y-83967D01*
X151610Y-87300D01*
X152870Y-89801D01*
X154760Y-91467D01*
X156965Y-92300D01*
X159170Y-91883D01*
X161060Y-90634D01*
X162320Y-88967D01*
G01X6548Y-105000D02*
Y-98700D01*
X10152Y-105000D01*
Y-98700D01*
G01X14650Y-105000D02*
X14023Y-104895D01*
X13475Y-104475D01*
X13005Y-103845D01*
X12692Y-103110D01*
X12535Y-102270D01*
Y-101430D01*
X12692Y-100590D01*
X13005Y-99855D01*
X13475Y-99225D01*
X14023Y-98805D01*
X14650Y-98700D01*
X15277Y-98805D01*
X15825Y-99225D01*
X16295Y-99855D01*
X16608Y-100590D01*
X16765Y-101430D01*
Y-102270D01*
X16608Y-103110D01*
X16295Y-103845D01*
X15825Y-104475D01*
X15277Y-104895D01*
X14650Y-105000D01*
G01X20950Y-105210D02*
X20793Y-105105D01*
Y-104895D01*
X20950Y-104790D01*
X21107Y-104895D01*
Y-105105D01*
X20950Y-105210D01*
G01X27250Y-105000D02*
Y-98700D01*
X26310Y-99960D01*
G01Y-105000D02*
X28190D01*
G01X33550D02*
X34098Y-104895D01*
X34725Y-104580D01*
X35117Y-104055D01*
X35273Y-103320D01*
X35117Y-102585D01*
X34647Y-101955D01*
X33942Y-101640D01*
X33158D01*
X32688Y-101430D01*
X32297Y-100905D01*
X32140Y-100170D01*
X32375Y-99435D01*
X32923Y-98910D01*
X33550Y-98700D01*
X34177Y-98910D01*
X34725Y-99435D01*
X34960Y-100170D01*
X34803Y-100905D01*
X34412Y-101430D01*
X33942Y-101640D01*
X33158D01*
X32453Y-101955D01*
X31983Y-102585D01*
X31827Y-103320D01*
X31983Y-104055D01*
X32375Y-104580D01*
X33002Y-104895D01*
X33550Y-105000D01*
G01X39850D02*
X40398Y-104895D01*
X41025Y-104580D01*
X41417Y-104055D01*
X41573Y-103320D01*
X41417Y-102585D01*
X40947Y-101955D01*
X40242Y-101640D01*
X39458D01*
X38988Y-101430D01*
X38597Y-100905D01*
X38440Y-100170D01*
X38675Y-99435D01*
X39223Y-98910D01*
X39850Y-98700D01*
X40477Y-98910D01*
X41025Y-99435D01*
X41260Y-100170D01*
X41103Y-100905D01*
X40712Y-101430D01*
X40242Y-101640D01*
X39458D01*
X38753Y-101955D01*
X38283Y-102585D01*
X38127Y-103320D01*
X38283Y-104055D01*
X38675Y-104580D01*
X39302Y-104895D01*
X39850Y-105000D01*
G01X45993Y-106155D02*
X46307Y-104790D01*
G01X50100Y-98700D02*
X51197Y-105000D01*
X52450Y-98700D01*
X53703Y-105000D01*
X54800Y-98700D01*
G01X60317Y-105000D02*
X57183D01*
Y-98700D01*
X60317D01*
G01X59063Y-101745D02*
X57183D01*
G01X63248Y-105000D02*
Y-98700D01*
X66852Y-105000D01*
Y-98700D01*
G01X76005Y-105000D02*
Y-98700D01*
G01X79295D02*
Y-105000D01*
G01Y-101850D02*
X76005D01*
G01X81600Y-98700D02*
X82697Y-105000D01*
X83950Y-98700D01*
X85203Y-105000D01*
X86300Y-98700D01*
G01X88292Y-105000D02*
X90250Y-98700D01*
X92208Y-105000D01*
G01X91503Y-102795D02*
X88997D01*
G01X101362Y-99750D02*
X101832Y-99120D01*
X102380Y-98805D01*
X103007Y-98700D01*
X103790Y-98910D01*
X104338Y-99435D01*
X104495Y-100065D01*
X104417Y-100695D01*
X104103Y-101220D01*
X102537Y-102270D01*
X101832Y-103005D01*
X101362Y-104055D01*
X101205Y-105000D01*
X104495D01*
G01X107348D02*
Y-98700D01*
X110952Y-105000D01*
Y-98700D01*
G01X113727Y-105000D02*
Y-98700D01*
X115293D01*
X115920Y-99015D01*
X116390Y-99435D01*
X116782Y-100065D01*
X117095Y-100800D01*
X117173Y-101850D01*
X117095Y-102900D01*
X116782Y-103635D01*
X116390Y-104265D01*
X115920Y-104685D01*
X115293Y-105000D01*
X113727D01*
G01X126483D02*
Y-98700D01*
X128442D01*
X129068Y-99015D01*
X129460Y-99435D01*
X129617Y-100275D01*
X129460Y-101115D01*
X128990Y-101640D01*
X128442Y-101955D01*
X126483D01*
G01X128442D02*
X129617Y-105000D01*
G01X132627D02*
Y-98700D01*
X134193D01*
X134820Y-99015D01*
X135290Y-99435D01*
X135682Y-100065D01*
X135995Y-100800D01*
X136073Y-101850D01*
X135995Y-102900D01*
X135682Y-103635D01*
X135290Y-104265D01*
X134820Y-104685D01*
X134193Y-105000D01*
X132627D01*
G01X140650Y-105210D02*
X140493Y-105105D01*
Y-104895D01*
X140650Y-104790D01*
X140807Y-104895D01*
Y-105105D01*
X140650Y-105210D01*
G01X22756Y125629D02*
X5306Y143079D01*
Y696763D01*
X10477Y701934D01*
Y716371D01*
X7673Y719175D01*
G01X13441Y501915D02*
Y511565D01*
X14073Y512197D01*
G01X15984Y573127D02*
Y563714D01*
X14073Y561803D01*
G01Y552000D02*
X9669Y556404D01*
Y565377D01*
X10914Y566622D01*
Y573061D01*
G01X105152Y1118381D02*
X109673Y1113860D01*
X115039D01*
X117807Y1116628D01*
X123216D01*
X130195Y1109649D01*
Y1052660D01*
X107946Y1030411D01*
Y983262D01*
X100215Y975531D01*
Y936687D01*
X104927Y931975D01*
Y797008D01*
X87319Y779400D01*
Y725308D01*
X69035Y707024D01*
X30037D01*
X26769Y710292D01*
X18475D01*
X15547Y707364D01*
G01X70865Y872278D02*
X68650Y870063D01*
X58106D01*
X38096Y850053D01*
X30570D01*
X26456Y845939D01*
X24363D01*
X19497Y841073D01*
Y837299D01*
X15547Y833349D01*
G01X70865Y890116D02*
X56817D01*
X46176Y879475D01*
Y876845D01*
X34377Y865046D01*
X30921D01*
X27163Y861288D01*
X24608D01*
X17055Y853735D01*
X15026D01*
X10780Y849489D01*
Y840393D01*
X7673Y837286D01*
G01X89338Y878294D02*
X89017Y878615D01*
X70441D01*
X63542Y871716D01*
X56891D01*
X41243Y856068D01*
X29935D01*
X27358Y853491D01*
X23449D01*
X19880Y849922D01*
Y845556D01*
X15547Y841223D01*
G01X70865Y866278D02*
X70765Y866378D01*
X59406D01*
X35247Y842219D01*
X33726D01*
X30288Y838781D01*
Y831961D01*
X27739Y829412D01*
X7673D01*
G01X91733Y899382D02*
X95482Y903131D01*
Y907850D01*
X93026Y910306D01*
X65508D01*
X43948Y888746D01*
X31698D01*
X28590Y885638D01*
X25660D01*
X19948Y879926D01*
Y872485D01*
X16116Y868653D01*
X14087D01*
X10630Y865196D01*
Y863865D01*
X7673Y860908D01*
G01X92633Y907404D02*
X67286D01*
X38829Y878947D01*
Y875961D01*
X35580Y872712D01*
X30395D01*
X27088Y869405D01*
X24683D01*
X19874Y864596D01*
Y861298D01*
X15547Y856971D01*
G01X48085Y919992D02*
X30995D01*
X27029Y916026D01*
X7673D01*
G01X45981Y911910D02*
X30321D01*
X26563Y908152D01*
X7673D01*
G01X47109Y975598D02*
X32038D01*
X27324Y970884D01*
X22357D01*
X18160Y975081D01*
X15547D01*
G01X51149Y967593D02*
X31029D01*
X27071Y963635D01*
X21599D01*
X18027Y967207D01*
X15547D01*
G01Y990829D02*
X18741Y994023D01*
X28280D01*
X30589Y991714D01*
X97384D01*
X98139Y990959D01*
G01X7673Y994766D02*
X12970D01*
X13922Y995718D01*
X28602D01*
X31754Y998870D01*
X38667D01*
X41298Y1001501D01*
X98577D01*
X100687Y999391D01*
G01X47833Y1085626D02*
X43791Y1081584D01*
X31501D01*
X28385Y1084700D01*
X20219D01*
X16896Y1081377D01*
X15551D01*
G01X47665Y1075692D02*
X45980Y1074007D01*
X31669D01*
X28385Y1077291D01*
X20892D01*
X17104Y1073503D01*
X15551D01*
G01X47540Y1136770D02*
X31459D01*
X27797Y1140432D01*
X7677D01*
G01X46992Y1129235D02*
X31334D01*
X28011Y1132558D01*
X7677D01*
G01X46320Y1215867D02*
X43541D01*
X35049Y1207375D01*
X31871D01*
X28082Y1203586D01*
X21010D01*
X16912Y1199488D01*
X15551D01*
G01X49856Y1208711D02*
X43037D01*
X33703Y1199377D01*
X31534D01*
X27745Y1195588D01*
X20842D01*
X16868Y1191614D01*
X15551D01*
G01X54654Y1244744D02*
X53728Y1245670D01*
X44719D01*
X43456Y1246933D01*
X30323D01*
X27377Y1249879D01*
X24093D01*
X21315Y1252657D01*
Y1255015D01*
X17787Y1258543D01*
X7677D01*
G01X55496Y1235735D02*
X46656D01*
X43877Y1238514D01*
X32007D01*
X28556Y1241965D01*
X24514D01*
X20894Y1245585D01*
Y1248364D01*
X18589Y1250669D01*
X7677D01*
G01X51432Y1279783D02*
X50206Y1281009D01*
X37100D01*
X35272Y1279181D01*
X30399D01*
X28221Y1281359D01*
X18682D01*
X15551Y1278228D01*
G01X51398Y1267290D02*
X42592D01*
X38443Y1271439D01*
X31454D01*
X28602Y1274291D01*
X7677D01*
G01X51060Y1263103D02*
X43096D01*
X36826Y1269373D01*
X29987D01*
X27808Y1267194D01*
X18711D01*
X15551Y1270354D01*
G01X33267Y1353031D02*
X25086D01*
X20885Y1357232D01*
Y1359640D01*
X19382Y1361143D01*
Y1389685D01*
X6889Y1402178D01*
Y1944762D01*
X22756Y1960629D01*
G01X25393Y1349094D02*
X18827Y1355660D01*
Y1358688D01*
X16760Y1360755D01*
X14431D01*
X12355Y1362831D01*
Y1392588D01*
X5389Y1399554D01*
Y2018262D01*
X22756Y2035629D01*
G01X25393Y1356968D02*
Y1359254D01*
X22322Y1362325D01*
Y1388764D01*
X8388Y1402698D01*
Y1864262D01*
X22756Y1878630D01*
G01X14691Y1559284D02*
Y1569583D01*
X14073Y1570201D01*
G01X11153Y1632285D02*
X10547Y1631679D01*
Y1613530D01*
X14073Y1610004D01*
G01X16552Y1632153D02*
Y1622286D01*
X14073Y1619807D01*
G01X70865Y860278D02*
X56255D01*
X33263Y837286D01*
G01X100719Y1318810D02*
X96536Y1314627D01*
Y1220443D01*
X105386Y1211593D01*
Y1142855D01*
X96798Y1134267D01*
Y1106868D01*
X104438Y1099228D01*
X114383D01*
X116554Y1097057D01*
X122998D01*
X125729Y1094326D01*
Y1057086D01*
X102668Y1034025D01*
Y986181D01*
X93000Y976513D01*
Y932553D01*
X99862Y925691D01*
Y882547D01*
X92382Y875067D01*
X78767D01*
X72260Y868560D01*
X59334D01*
X39138Y848364D01*
X32224D01*
X28259Y844399D01*
Y836219D01*
X25389Y833349D01*
G01X33263Y829412D02*
X58129Y854278D01*
X83162D01*
X102076Y873192D01*
Y928240D01*
X96082Y934234D01*
Y976018D01*
X104349Y984285D01*
Y1032662D01*
X127253Y1055566D01*
Y1101979D01*
X122802Y1106430D01*
X111092D01*
X99954Y1117568D01*
Y1131029D01*
X108186Y1139261D01*
Y1214475D01*
X100719Y1221942D01*
Y1306810D01*
G01X48433Y866179D02*
X39791Y857537D01*
X25955D01*
X25389Y856971D01*
G01X33263Y860908D02*
X40097D01*
X48467Y869278D01*
G01X25389Y896341D02*
X45789D01*
G01X50864Y904196D02*
X50845Y904215D01*
X46023D01*
G01D02*
X25389D01*
G01X47835Y960098D02*
X42110D01*
X38938Y963270D01*
X33263D01*
G01X51960Y953195D02*
X40847D01*
X38646Y955396D01*
X33263D01*
G01X25389Y1022325D02*
X48203D01*
G01X119920Y1062165D02*
X110384Y1052629D01*
X63319D01*
X46382Y1069566D01*
X33267D01*
G01Y1061692D02*
X47474D01*
G01X33267Y1116810D02*
X45190D01*
X47414Y1114586D01*
G01X33267Y1124684D02*
X44051D01*
X47077Y1121658D01*
G01X45815Y1202354D02*
X35261Y1191800D01*
X31702D01*
X25393Y1185491D01*
Y1183740D01*
G01X46566Y1194825D02*
X35879Y1184138D01*
X31501D01*
X25393Y1178030D01*
Y1175866D01*
G01X33267Y1234921D02*
X43093D01*
X46404Y1231610D01*
G01X25393Y1254606D02*
X39344D01*
X46491Y1247459D01*
X78570D01*
X90477Y1259366D01*
Y1320731D01*
X91077Y1321331D01*
X91240D01*
X100719Y1330810D01*
G01X33267Y1258543D02*
X38442D01*
X47096Y1249889D01*
X77220D01*
X87665Y1260334D01*
Y1323756D01*
X100719Y1336810D01*
G01X33267Y1266417D02*
X37302D01*
X46086Y1257633D01*
X51127D01*
G01X33267Y1242795D02*
X45718D01*
G01X51331Y1271544D02*
X43335D01*
X40588Y1274291D01*
X33267D01*
G01X25393Y1278228D02*
X28580D01*
X29130Y1277678D01*
X40908D01*
X42956Y1275630D01*
X51432D01*
G01X51296Y1284038D02*
X49084Y1286250D01*
X40597D01*
X38385Y1284038D01*
X35140D01*
X33267Y1282165D01*
G01X46980Y1345843D02*
X47803D01*
X51763Y1349803D01*
X62542D01*
X67356Y1344989D01*
Y1326892D01*
X71045Y1323203D01*
X74602D01*
G01Y1318203D02*
X71877D01*
X65180Y1324900D01*
Y1344280D01*
X61817Y1347643D01*
X51866D01*
X46980Y1342757D01*
Y1340843D01*
G01X25393Y1388464D02*
X35208D01*
X38710Y1384962D01*
Y1361115D01*
X43571Y1356254D01*
X83013D01*
X95458Y1343809D01*
X99119D01*
X105726Y1337202D01*
Y1224830D01*
X111486Y1219070D01*
Y1136973D01*
X102924Y1128411D01*
Y1120609D01*
X105152Y1118381D01*
G01X72180Y690710D02*
X76041D01*
X77828Y692497D01*
Y699152D01*
X80269Y701593D01*
G01X91294Y926951D02*
X90911Y927334D01*
X73867D01*
X54014Y907481D01*
Y904196D01*
G01X51263Y1253378D02*
Y1257497D01*
X51127Y1257633D01*
G01X61866Y1309190D02*
X60722Y1310334D01*
Y1325314D01*
X57833Y1328203D01*
X54130D01*
G01X58752Y1302746D02*
Y1306076D01*
X61866Y1309190D01*
G01X63061Y1302746D02*
X58752D01*
G01X50331Y1302680D02*
X54542D01*
X54543Y1302681D01*
G01X54130Y1323203D02*
X56908D01*
X58526Y1321585D01*
Y1312978D01*
X54543Y1308995D01*
G01X50331Y1302680D02*
Y1304783D01*
X54543Y1308995D01*
G01X71909Y1302580D02*
X67569D01*
X67568Y1302581D01*
G01Y1307829D02*
X62696Y1312701D01*
Y1326559D01*
X56052Y1333203D01*
X54130D01*
G01X71909Y1302580D02*
Y1303488D01*
X67568Y1307829D01*
G01X74602Y1328203D02*
X70340D01*
G01X52227Y1341972D02*
X61734D01*
X61866Y1342104D01*
G01X62637Y1782985D02*
Y1786356D01*
X64356Y1788075D01*
G01D02*
X66083D01*
X70376Y1783782D01*
Y1780543D01*
G01X119920Y416102D02*
X94857D01*
X93223Y417736D01*
G01X100595Y690710D02*
Y693073D01*
X99221Y694447D01*
X90955D01*
X88681Y696721D01*
Y698443D01*
G01X84533D02*
X88681D01*
G01X92980Y690710D02*
X100595D01*
G01X80269Y701593D02*
X84533D01*
G01D02*
Y703910D01*
X87363Y706740D01*
Y708496D01*
G01D02*
X91000D01*
X93165Y706331D01*
G01X92860Y701593D02*
X93165Y701898D01*
Y706331D01*
G01X139920Y754134D02*
X129251D01*
X124808Y758577D01*
X102883D01*
X95775Y751469D01*
G01X119920Y1062165D02*
X117944Y1064141D01*
X93722D01*
X90920Y1066943D01*
Y1131623D01*
X103051Y1143754D01*
Y1210919D01*
X93179Y1220791D01*
Y1317270D01*
X100719Y1324810D01*
G01Y1346065D02*
Y1385318D01*
X90055Y1395982D01*
Y1448140D01*
X95236Y1453321D01*
G01D02*
X95426Y1453131D01*
X100019D01*
G01X88624Y1754902D02*
X90157D01*
X93781Y1758526D01*
Y1773124D01*
X92026Y1774879D01*
G01X84417Y1754902D02*
X88624D01*
G01X81591Y1748227D02*
X77545D01*
X75198Y1750574D01*
G01D02*
Y1752886D01*
X77214Y1754902D01*
X80349D01*
G01X85376Y1780543D02*
Y1778567D01*
X87931Y1776012D01*
X90893D01*
X92026Y1774879D01*
G01X103928Y28320D02*
Y32853D01*
G01X108995Y20080D02*
Y24248D01*
X106958Y26285D01*
G01X103843Y24203D02*
X104876D01*
X106958Y26285D01*
G01X119920Y28071D02*
X108744D01*
X106958Y26285D01*
G01X108995Y15847D02*
Y20080D01*
G01X104932Y41803D02*
X101430D01*
G01X107405Y49898D02*
X107570Y49733D01*
X113546D01*
X115208Y48071D01*
X119920D01*
G01X108090Y46285D02*
Y47822D01*
X107405Y48507D01*
Y49898D01*
G01X103928Y32853D02*
X105203D01*
X107037Y34687D01*
G01X103928Y37438D02*
Y32853D01*
G01X119920Y38071D02*
X110421D01*
X107037Y34687D01*
G01X107263Y75055D02*
Y72244D01*
G01X119920Y58071D02*
X111950D01*
X111771Y58250D01*
X109054D01*
G01D02*
X105877D01*
G01X106836Y376461D02*
X107195Y376102D01*
X119920D01*
G01X103668Y376580D02*
Y371909D01*
G01Y381386D02*
Y376580D01*
G01X106836Y376461D02*
X106717Y376580D01*
X103668D01*
G01Y391220D02*
Y386235D01*
G01Y396024D02*
Y391220D01*
G01X106709Y391219D02*
X114803D01*
X119920Y386102D01*
G01X103668Y391220D02*
X106708D01*
X106709Y391219D01*
G01X100794Y400352D02*
Y402138D01*
X105451Y406795D01*
G01X119920Y396102D02*
X114603D01*
X114498Y396207D01*
G01X103944Y400352D02*
X114108D01*
X119858Y406102D01*
X119920D01*
G01X104206Y720745D02*
Y715937D01*
G01Y725457D02*
Y720745D01*
G01X119920Y724134D02*
X114536D01*
X113302Y725368D01*
X107025D01*
G01X104206Y725457D02*
X106936D01*
X107025Y725368D01*
G01X104206Y730398D02*
Y735248D01*
G01X101520Y749481D02*
Y750559D01*
X105087Y754126D01*
G01X119920Y744134D02*
X114834D01*
X113829Y745139D01*
X106935D01*
G01D02*
X104346D01*
G01X104206Y735248D02*
Y739962D01*
G01X119920Y734134D02*
X114441D01*
X113356Y735219D01*
X107173D01*
G01X104206Y735248D02*
X107144D01*
X107173Y735219D01*
G01X119920Y754134D02*
X119858D01*
X119850Y754126D01*
X109315D01*
X104670Y749481D01*
G01X104339Y1072226D02*
Y1067515D01*
G01X104432Y1096403D02*
X107351Y1093484D01*
G01D02*
X108670Y1092165D01*
X119920D01*
G01X104339Y1087095D02*
Y1081791D01*
G01Y1092036D02*
Y1087095D01*
G01Y1081791D02*
X107235Y1081773D01*
Y1081791D01*
G01D02*
X107261Y1081765D01*
X115317D01*
X115717Y1082165D01*
X119920D01*
G01X104339Y1076901D02*
Y1072226D01*
G01X107215Y1072208D02*
X107552D01*
G01D02*
X107595Y1072165D01*
X119920D01*
G01X107552Y1072208D02*
X104339Y1072226D01*
G01X108779Y1105760D02*
X98459Y1116080D01*
Y1132266D01*
X106786Y1140593D01*
Y1213895D01*
X98241Y1222440D01*
Y1310332D01*
X100719Y1312810D01*
G01X105880Y1102535D02*
Y1102861D01*
X108779Y1105760D01*
G01X109030Y1102535D02*
X114534D01*
X114904Y1102165D01*
X119920D01*
G01Y1430197D02*
X116076Y1434041D01*
X106962D01*
G01X103377Y1419492D02*
X106921D01*
G01X103377Y1424340D02*
Y1419492D01*
G01Y1429195D02*
Y1424340D01*
G01X106921Y1419492D02*
X118288D01*
X118993Y1420197D01*
X119920D01*
G01Y1440197D02*
X111165D01*
X106763Y1444599D01*
G01D02*
X103443Y1447919D01*
G01X103377Y1438980D02*
Y1434041D01*
G01Y1443743D02*
Y1438980D01*
G01X106962Y1434041D02*
X103377D01*
G01X107006Y1452651D02*
X109466Y1450191D01*
X119852D01*
X119858Y1450197D01*
X119920D01*
G01X103169Y1453131D02*
X106526D01*
X107006Y1452651D01*
G01X104827Y1765722D02*
Y1760827D01*
G01Y1770527D02*
Y1765722D01*
G01X107355Y1770437D02*
X117711D01*
X119920Y1768228D01*
G01X104827Y1770527D02*
X107265D01*
X107355Y1770437D01*
G01X107391Y1794460D02*
X105383D01*
X103671Y1796172D01*
Y1798224D01*
G01X119920Y1788228D02*
X110581D01*
X107220Y1791589D01*
G01D02*
X106572D01*
X104930Y1789947D01*
G01X104827Y1780542D02*
X107371D01*
X107373Y1780544D01*
G01X104827Y1785571D02*
Y1780542D01*
G01Y1775514D02*
Y1780542D01*
G01X107373Y1780544D02*
X112823D01*
X115139Y1778228D01*
X119920D01*
G01Y1798228D02*
X115920D01*
X115916Y1798224D01*
X110825D01*
X106819Y1802230D01*
G01D02*
X106821Y1802232D01*
Y1798224D01*
G01X139920Y48071D02*
X139921Y48070D01*
X154202D01*
X157558Y51426D01*
G01X139920Y68071D02*
X143858D01*
X147858Y68070D01*
X147918Y68130D01*
X155313D01*
G01X139920Y396102D02*
X151760D01*
X156865Y401207D01*
G01X156321Y415048D02*
X148721D01*
X147667Y416102D01*
X139920D01*
G01Y744134D02*
X151741D01*
X156610Y749003D01*
Y751063D01*
G01X139920Y764134D02*
X143858D01*
X147858Y764133D01*
X147956Y764231D01*
X155515D01*
G01X139920Y1092165D02*
X147988D01*
X156854Y1101031D01*
G01X139920Y1112165D02*
X145661D01*
X147858Y1112164D01*
X148671Y1112977D01*
X156117D01*
G01X139920Y1440197D02*
X148284D01*
X159192Y1451105D01*
G01X139920Y1460197D02*
X153901D01*
X156355Y1462651D01*
G01X139920Y1480197D02*
X147858D01*
X148758Y1481097D01*
X152213D01*
X153036Y1480274D01*
X155816D01*
G01X156452Y1800821D02*
Y1798275D01*
X146405Y1788228D01*
X139920D01*
G01Y1808228D02*
X144389D01*
X147858Y1808227D01*
X149809D01*
X155413Y1813831D01*
Y1815631D01*
G01X156526Y56744D02*
Y54258D01*
X157558Y53226D01*
Y51426D01*
G01X156865Y401207D02*
Y403217D01*
X155340Y404742D01*
Y407575D01*
G01X161256Y415045D02*
X156324D01*
X156321Y415048D01*
G01X155800Y756757D02*
Y753673D01*
X156610Y752863D01*
Y751063D01*
G01X156854Y1101031D02*
Y1102831D01*
X156128Y1103557D01*
Y1106853D01*
G01X156117Y1112977D02*
X159062D01*
X159070Y1112985D01*
X160870D01*
G01X157102Y1457084D02*
Y1453195D01*
X159192Y1451105D01*
G01X155690Y1807740D02*
Y1805940D01*
X156452Y1805178D01*
Y1800821D01*
G01X158559Y1820360D02*
Y1818877D01*
X155413Y1815731D01*
Y1815631D01*
G01X202000Y-72000D02*
Y-80000D01*
X206000D01*
G01X213800D02*
Y-74667D01*
G01Y-75600D02*
X213400Y-75067D01*
X212800Y-74800D01*
X212100Y-74667D01*
X211400Y-74933D01*
X210800Y-75467D01*
X210400Y-76267D01*
X210200Y-77333D01*
X210400Y-78400D01*
X210800Y-79200D01*
X211400Y-79733D01*
X212100Y-80000D01*
X212800Y-79867D01*
X213400Y-79467D01*
X213800Y-78934D01*
G01X217900Y-82400D02*
X218500Y-82667D01*
X219300Y-82400D01*
X219800Y-81867D01*
X220200Y-81200D01*
X220800Y-79067D01*
X222100Y-74667D01*
G01X218900D02*
X220800Y-79067D01*
G01X226500Y-76400D02*
X229700D01*
X229400Y-75467D01*
X228900Y-74933D01*
X228200Y-74667D01*
X227500Y-74800D01*
X226900Y-75200D01*
X226500Y-76133D01*
X226300Y-76934D01*
Y-77733D01*
X226500Y-78533D01*
X227000Y-79333D01*
X227600Y-79867D01*
X228300Y-80000D01*
X229000Y-79733D01*
X229700Y-78934D01*
G01X234600Y-80000D02*
Y-74667D01*
G01Y-75733D02*
X235100Y-75200D01*
X235600Y-74800D01*
X236300Y-74667D01*
X236800Y-74800D01*
X237400Y-75200D01*
G01X225500Y-122000D02*
Y-130000D01*
G01X223200Y-122000D02*
X227800D01*
G01X233500Y-124667D02*
Y-130000D01*
G01Y-122533D02*
X233300Y-122400D01*
Y-122133D01*
X233500Y-122000D01*
X233700Y-122133D01*
Y-122400D01*
X233500Y-122533D01*
G01X239800Y-130000D02*
Y-124667D01*
G01Y-126000D02*
X240200Y-125333D01*
X240800Y-124800D01*
X241600Y-124667D01*
X242300Y-124800D01*
X242900Y-125333D01*
X243200Y-126267D01*
Y-130000D01*
G01X251300D02*
Y-124667D01*
G01Y-125600D02*
X250900Y-125067D01*
X250300Y-124800D01*
X249600Y-124667D01*
X248900Y-124933D01*
X248300Y-125467D01*
X247900Y-126267D01*
X247700Y-127333D01*
X247900Y-128400D01*
X248300Y-129200D01*
X248900Y-129733D01*
X249600Y-130000D01*
X250300Y-129867D01*
X250900Y-129467D01*
X251300Y-128934D01*
G01X235500Y-97000D02*
Y-105000D01*
G01X233200Y-97000D02*
X237800D01*
G01X243500Y-105000D02*
X242700Y-104867D01*
X242000Y-104333D01*
X241400Y-103533D01*
X241000Y-102600D01*
X240800Y-101533D01*
Y-100467D01*
X241000Y-99400D01*
X241400Y-98467D01*
X242000Y-97667D01*
X242700Y-97133D01*
X243500Y-97000D01*
X244300Y-97133D01*
X245000Y-97667D01*
X245600Y-98467D01*
X246000Y-99400D01*
X246200Y-100467D01*
Y-101533D01*
X246000Y-102600D01*
X245600Y-103533D01*
X245000Y-104333D01*
X244300Y-104867D01*
X243500Y-105000D01*
G01X249500D02*
Y-97000D01*
X251900D01*
X252700Y-97400D01*
X253300Y-98333D01*
X253500Y-99400D01*
X253300Y-100467D01*
X252800Y-101267D01*
X251900Y-101667D01*
X249500D01*
G01X255500Y-80000D02*
Y-72000D01*
X254300Y-73600D01*
G01Y-80000D02*
X256700D01*
G01X328600Y-123333D02*
X329200Y-122533D01*
X329900Y-122133D01*
X330700Y-122000D01*
X331700Y-122267D01*
X332400Y-122933D01*
X332600Y-123733D01*
X332500Y-124534D01*
X332100Y-125200D01*
X330100Y-126533D01*
X329200Y-127467D01*
X328600Y-128800D01*
X328400Y-130000D01*
X332600D01*
G01X338500Y-122000D02*
X337700Y-122267D01*
X337100Y-122933D01*
X336700Y-123733D01*
X336400Y-124800D01*
X336300Y-126000D01*
X336400Y-127200D01*
X336700Y-128267D01*
X337100Y-129067D01*
X337700Y-129733D01*
X338500Y-130000D01*
X339300Y-129733D01*
X339900Y-129067D01*
X340300Y-128267D01*
X340600Y-127200D01*
X340700Y-126000D01*
X340600Y-124800D01*
X340300Y-123733D01*
X339900Y-122933D01*
X339300Y-122267D01*
X338500Y-122000D01*
G01X346500Y-130000D02*
Y-122000D01*
X345300Y-123600D01*
G01Y-130000D02*
X347700D01*
G01X352300Y-128400D02*
X352900Y-129333D01*
X353700Y-129867D01*
X354600Y-130000D01*
X355400Y-129867D01*
X356200Y-129200D01*
X356700Y-128400D01*
X356800Y-127600D01*
X356600Y-126667D01*
X355900Y-126000D01*
X355200Y-125733D01*
X354300D01*
G01X355200D02*
X355800Y-125333D01*
X356300Y-124667D01*
X356500Y-123867D01*
X356300Y-123067D01*
X355800Y-122400D01*
X354900Y-122000D01*
X354000Y-122133D01*
X353100Y-122667D01*
G01X360700Y-130267D02*
X364300Y-122000D01*
G01X370500D02*
X369700Y-122267D01*
X369100Y-122933D01*
X368700Y-123733D01*
X368400Y-124800D01*
X368300Y-126000D01*
X368400Y-127200D01*
X368700Y-128267D01*
X369100Y-129067D01*
X369700Y-129733D01*
X370500Y-130000D01*
X371300Y-129733D01*
X371900Y-129067D01*
X372300Y-128267D01*
X372600Y-127200D01*
X372700Y-126000D01*
X372600Y-124800D01*
X372300Y-123733D01*
X371900Y-122933D01*
X371300Y-122267D01*
X370500Y-122000D01*
G01X378500Y-130000D02*
Y-122000D01*
X377300Y-123600D01*
G01Y-130000D02*
X379700D01*
G01X384700Y-130267D02*
X388300Y-122000D01*
G01X394500D02*
X393700Y-122267D01*
X393100Y-122933D01*
X392700Y-123733D01*
X392400Y-124800D01*
X392300Y-126000D01*
X392400Y-127200D01*
X392700Y-128267D01*
X393100Y-129067D01*
X393700Y-129733D01*
X394500Y-130000D01*
X395300Y-129733D01*
X395900Y-129067D01*
X396300Y-128267D01*
X396600Y-127200D01*
X396700Y-126000D01*
X396600Y-124800D01*
X396300Y-123733D01*
X395900Y-122933D01*
X395300Y-122267D01*
X394500Y-122000D01*
G01X400800Y-129067D02*
X401500Y-129733D01*
X402300Y-130000D01*
X403100Y-129733D01*
X403800Y-128934D01*
X404300Y-127733D01*
X404500Y-126533D01*
Y-125067D01*
X404300Y-123867D01*
X403800Y-122800D01*
X403200Y-122267D01*
X402500Y-122000D01*
X401700Y-122267D01*
X401100Y-122800D01*
X400700Y-123600D01*
X400500Y-124667D01*
X400700Y-125600D01*
X401200Y-126533D01*
X401800Y-127067D01*
X402500Y-127200D01*
X403300Y-126934D01*
X403900Y-126267D01*
X404500Y-125067D01*
G01X328300Y-105000D02*
Y-97000D01*
X330300D01*
X331100Y-97400D01*
X331700Y-97933D01*
X332200Y-98733D01*
X332600Y-99667D01*
X332700Y-101000D01*
X332600Y-102333D01*
X332200Y-103267D01*
X331700Y-104067D01*
X331100Y-104600D01*
X330300Y-105000D01*
X328300D01*
G01X336000D02*
X338500Y-97000D01*
X341000Y-105000D01*
G01X340100Y-102200D02*
X336900D01*
G01X346500Y-97000D02*
Y-105000D01*
G01X344200Y-97000D02*
X348800D01*
G01X352600Y-101667D02*
X353300Y-100733D01*
X353900Y-100200D01*
X354700Y-99933D01*
X355400Y-100200D01*
X355900Y-100733D01*
X356300Y-101533D01*
X356400Y-102467D01*
X356300Y-103267D01*
X355900Y-104067D01*
X355300Y-104733D01*
X354600Y-105000D01*
X353800Y-104733D01*
X353100Y-103934D01*
X352700Y-102733D01*
X352600Y-101400D01*
X352800Y-99667D01*
X353100Y-98733D01*
X353600Y-97800D01*
X354300Y-97133D01*
X355000Y-97000D01*
X355700Y-97267D01*
X356200Y-97933D01*
G01X359900Y-105000D02*
Y-97000D01*
X362500Y-103667D01*
X365100Y-97000D01*
Y-105000D01*
G01X370500Y-97000D02*
Y-105000D01*
G01X368200Y-97000D02*
X372800D01*
G01X379300Y-100733D02*
X379700Y-100333D01*
X380000Y-99667D01*
X380200Y-98733D01*
X380000Y-97933D01*
X379600Y-97400D01*
X378900Y-97000D01*
X376200D01*
Y-105000D01*
X379500D01*
X380200Y-104467D01*
X380600Y-103667D01*
X380800Y-102733D01*
X380600Y-101800D01*
X380000Y-101000D01*
X379300Y-100733D01*
X376200D01*
G01X386500Y-105000D02*
X387200Y-104867D01*
X388000Y-104467D01*
X388500Y-103800D01*
X388700Y-102867D01*
X388500Y-101934D01*
X387900Y-101133D01*
X387000Y-100733D01*
X386000D01*
X385400Y-100467D01*
X384900Y-99800D01*
X384700Y-98867D01*
X385000Y-97933D01*
X385700Y-97267D01*
X386500Y-97000D01*
X387300Y-97267D01*
X388000Y-97933D01*
X388300Y-98867D01*
X388100Y-99800D01*
X387600Y-100467D01*
X387000Y-100733D01*
X386000D01*
X385100Y-101133D01*
X384500Y-101934D01*
X384300Y-102867D01*
X384500Y-103800D01*
X385000Y-104467D01*
X385800Y-104867D01*
X386500Y-105000D01*
G01X394500D02*
X395200Y-104867D01*
X396000Y-104467D01*
X396500Y-103800D01*
X396700Y-102867D01*
X396500Y-101934D01*
X395900Y-101133D01*
X395000Y-100733D01*
X394000D01*
X393400Y-100467D01*
X392900Y-99800D01*
X392700Y-98867D01*
X393000Y-97933D01*
X393700Y-97267D01*
X394500Y-97000D01*
X395300Y-97267D01*
X396000Y-97933D01*
X396300Y-98867D01*
X396100Y-99800D01*
X395600Y-100467D01*
X395000Y-100733D01*
X394000D01*
X393100Y-101133D01*
X392500Y-101934D01*
X392300Y-102867D01*
X392500Y-103800D01*
X393000Y-104467D01*
X393800Y-104867D01*
X394500Y-105000D01*
G01X400000D02*
X402500Y-97000D01*
X405000Y-105000D01*
G01X404100Y-102200D02*
X400900D01*
G01X410500Y-97000D02*
X409700Y-97267D01*
X409100Y-97933D01*
X408700Y-98733D01*
X408400Y-99800D01*
X408300Y-101000D01*
X408400Y-102200D01*
X408700Y-103267D01*
X409100Y-104067D01*
X409700Y-104733D01*
X410500Y-105000D01*
X411300Y-104733D01*
X411900Y-104067D01*
X412300Y-103267D01*
X412600Y-102200D01*
X412700Y-101000D01*
X412600Y-99800D01*
X412300Y-98733D01*
X411900Y-97933D01*
X411300Y-97267D01*
X410500Y-97000D01*
G01X350500Y-72000D02*
Y-80000D01*
G01X348200Y-72000D02*
X352800D01*
G01X356600Y-76667D02*
X357300Y-75733D01*
X357900Y-75200D01*
X358700Y-74933D01*
X359400Y-75200D01*
X359900Y-75733D01*
X360300Y-76533D01*
X360400Y-77467D01*
X360300Y-78267D01*
X359900Y-79067D01*
X359300Y-79733D01*
X358600Y-80000D01*
X357800Y-79733D01*
X357100Y-78934D01*
X356700Y-77733D01*
X356600Y-76400D01*
X356800Y-74667D01*
X357100Y-73733D01*
X357600Y-72800D01*
X358300Y-72133D01*
X359000Y-72000D01*
X359700Y-72267D01*
X360200Y-72933D01*
G01X363900Y-80000D02*
Y-72000D01*
X366500Y-78667D01*
X369100Y-72000D01*
Y-80000D01*
G01X375100Y-76000D02*
X377100D01*
Y-78400D01*
X376500Y-79200D01*
X375800Y-79733D01*
X374800Y-80000D01*
X373800Y-79733D01*
X373100Y-79200D01*
X372500Y-78400D01*
X372100Y-77467D01*
X371900Y-76400D01*
Y-75467D01*
X372100Y-74667D01*
X372500Y-73733D01*
X373100Y-72933D01*
X373700Y-72400D01*
X374500Y-72000D01*
X375200D01*
X376000Y-72267D01*
X376600Y-72800D01*
G01X379500Y-82667D02*
X385500D01*
G01X388500Y-80000D02*
Y-72000D01*
X390900D01*
X391700Y-72400D01*
X392300Y-73333D01*
X392500Y-74400D01*
X392300Y-75467D01*
X391800Y-76267D01*
X390900Y-76667D01*
X388500D01*
G01X396300Y-80000D02*
Y-72000D01*
X398300D01*
X399100Y-72400D01*
X399700Y-72933D01*
X400200Y-73733D01*
X400600Y-74667D01*
X400700Y-76000D01*
X400600Y-77333D01*
X400200Y-78267D01*
X399700Y-79067D01*
X399100Y-79600D01*
X398300Y-80000D01*
X396300D01*
G01X407300Y-75733D02*
X407700Y-75333D01*
X408000Y-74667D01*
X408200Y-73733D01*
X408000Y-72933D01*
X407600Y-72400D01*
X406900Y-72000D01*
X404200D01*
Y-80000D01*
X407500D01*
X408200Y-79467D01*
X408600Y-78667D01*
X408800Y-77733D01*
X408600Y-76800D01*
X408000Y-76000D01*
X407300Y-75733D01*
X404200D01*
G01X411500Y-82667D02*
X417500D01*
G01X420000Y-80000D02*
X422500Y-72000D01*
X425000Y-80000D01*
G01X424100Y-77200D02*
X420900D01*
G01X427500Y-82667D02*
X433500D01*
G01X439300Y-75733D02*
X439700Y-75333D01*
X440000Y-74667D01*
X440200Y-73733D01*
X440000Y-72933D01*
X439600Y-72400D01*
X438900Y-72000D01*
X436200D01*
Y-80000D01*
X439500D01*
X440200Y-79467D01*
X440600Y-78667D01*
X440800Y-77733D01*
X440600Y-76800D01*
X440000Y-76000D01*
X439300Y-75733D01*
X436200D01*
G01X444300Y-80000D02*
Y-72000D01*
X446300D01*
X447100Y-72400D01*
X447700Y-72933D01*
X448200Y-73733D01*
X448600Y-74667D01*
X448700Y-76000D01*
X448600Y-77333D01*
X448200Y-78267D01*
X447700Y-79067D01*
X447100Y-79600D01*
X446300Y-80000D01*
X444300D01*
G01X443000Y-130000D02*
X445500Y-122000D01*
X448000Y-130000D01*
G01X447100Y-127200D02*
X443900D01*
G01X473000Y-130000D02*
Y-122000D01*
X471800Y-123600D01*
G01Y-130000D02*
X474200D01*
G01X479100Y-126667D02*
X479800Y-125733D01*
X480400Y-125200D01*
X481200Y-124933D01*
X481900Y-125200D01*
X482400Y-125733D01*
X482800Y-126533D01*
X482900Y-127467D01*
X482800Y-128267D01*
X482400Y-129067D01*
X481800Y-129733D01*
X481100Y-130000D01*
X480300Y-129733D01*
X479600Y-128934D01*
X479200Y-127733D01*
X479100Y-126400D01*
X479300Y-124667D01*
X479600Y-123733D01*
X480100Y-122800D01*
X480800Y-122133D01*
X481500Y-122000D01*
X482200Y-122267D01*
X482700Y-122933D01*
G54D29*
X72180Y675710D03*
Y680710D03*
Y685710D03*
Y690710D03*
X92980Y680710D03*
Y675710D03*
Y690710D03*
Y685710D03*
G54D38*
X173385Y32520D03*
Y207520D03*
Y382520D03*
X173386Y557520D03*
Y732520D03*
X173385Y907520D03*
Y1082520D03*
Y1257520D03*
Y1432520D03*
Y1607520D03*
Y1782520D03*
Y1957520D03*
G54D39*
Y21890D03*
X183385Y32520D03*
Y21890D03*
X193385Y32520D03*
Y21890D03*
X173385Y196890D03*
X183385D03*
X193385D03*
X183385Y207520D03*
X193385D03*
X173385Y371890D03*
X183385D03*
X193385D03*
X183385Y382520D03*
X193385D03*
X173386Y546890D03*
X183386Y557520D03*
Y546890D03*
X193386Y557520D03*
Y546890D03*
X173386Y721890D03*
X183386Y732520D03*
Y721890D03*
X193386Y732520D03*
Y721890D03*
X173385Y896890D03*
X183385D03*
X193385D03*
X183385Y907520D03*
X193385D03*
X173385Y1071890D03*
X183385D03*
X193385D03*
X183385Y1082520D03*
X193385D03*
X173385Y1246890D03*
X183385Y1257520D03*
Y1246890D03*
X193385Y1257520D03*
Y1246890D03*
X173385Y1421890D03*
X183385Y1432520D03*
Y1421890D03*
X193385Y1432520D03*
Y1421890D03*
X173385Y1596890D03*
X183385D03*
X193385D03*
X183385Y1607520D03*
X193385D03*
X173385Y1771890D03*
X183385D03*
X193385D03*
X183385Y1782520D03*
X193385D03*
X173385Y1946890D03*
X183385Y1957520D03*
Y1946890D03*
X193385Y1957520D03*
Y1946890D03*
X203385Y32520D03*
Y21890D03*
X213385Y32520D03*
Y21890D03*
X203385Y196890D03*
X213385D03*
X203385Y207520D03*
X213385D03*
X203385Y371890D03*
X213385D03*
X203385Y382520D03*
X213385D03*
X203386Y557520D03*
Y546890D03*
X213386Y557520D03*
Y546890D03*
X203386Y732520D03*
Y721890D03*
X213386Y732520D03*
Y721890D03*
X203385Y896890D03*
X213385D03*
X203385Y907520D03*
X213385D03*
X203385Y1071890D03*
X213385D03*
X203385Y1082520D03*
X213385D03*
X203385Y1257520D03*
Y1246890D03*
X213385Y1257520D03*
Y1246890D03*
X203385Y1432520D03*
Y1421890D03*
X213385Y1432520D03*
Y1421890D03*
X203385Y1596890D03*
X213385D03*
X203385Y1607520D03*
X213385D03*
X203385Y1771890D03*
X213385D03*
X203385Y1782520D03*
X213385D03*
X203385Y1957520D03*
Y1946890D03*
X213385Y1957520D03*
Y1946890D03*
X223385Y32520D03*
Y21890D03*
X233385Y32520D03*
Y21890D03*
X243385Y32520D03*
Y21890D03*
X223385Y196890D03*
X233385D03*
X243385D03*
X223385Y207520D03*
X233385D03*
X243385D03*
X223385Y371890D03*
X233385D03*
X243385D03*
X223385Y382520D03*
X233385D03*
X243385D03*
X223386Y557520D03*
Y546890D03*
X233386Y557520D03*
Y546890D03*
X243386Y557520D03*
Y546890D03*
X223386Y732520D03*
Y721890D03*
X233386Y732520D03*
Y721890D03*
X243386Y732520D03*
Y721890D03*
X223385Y896890D03*
X233385D03*
X243385D03*
X223385Y907520D03*
X233385D03*
X243385D03*
X223385Y1071890D03*
X233385D03*
X243385D03*
X223385Y1082520D03*
X233385D03*
X243385D03*
X223385Y1257520D03*
Y1246890D03*
X233385Y1257520D03*
Y1246890D03*
X243385Y1257520D03*
Y1246890D03*
X223385Y1432520D03*
Y1421890D03*
X233385Y1432520D03*
Y1421890D03*
X243385Y1432520D03*
Y1421890D03*
X223385Y1596890D03*
X233385D03*
X243385D03*
X223385Y1607520D03*
X233385D03*
X243385D03*
X223385Y1771890D03*
X233385D03*
X243385D03*
X223385Y1782520D03*
X233385D03*
X243385D03*
X223385Y1957520D03*
Y1946890D03*
X233385Y1957520D03*
Y1946890D03*
X243385Y1957520D03*
Y1946890D03*
X253385Y21890D03*
Y32520D03*
X263385Y21890D03*
Y32520D03*
X253385Y196890D03*
X263385D03*
X253385Y207520D03*
X263385D03*
X253385Y371890D03*
X263385D03*
X253385Y382520D03*
X263385D03*
X253386Y546890D03*
Y557520D03*
X263386Y546890D03*
Y557520D03*
X253386Y721890D03*
Y732520D03*
X263386Y721890D03*
Y732520D03*
X253385Y896890D03*
X263385D03*
X253385Y907520D03*
X263385D03*
X253385Y1071890D03*
X263385D03*
X253385Y1082520D03*
X263385D03*
X253385Y1246890D03*
Y1257520D03*
X263385Y1246890D03*
Y1257520D03*
X253385Y1421890D03*
Y1432520D03*
X263385Y1421890D03*
Y1432520D03*
X253385Y1596890D03*
X263385D03*
X253385Y1607520D03*
X263385D03*
X253385Y1771890D03*
X263385D03*
X253385Y1782520D03*
X263385D03*
X253385Y1946890D03*
Y1957520D03*
X263385Y1946890D03*
Y1957520D03*
X273385Y21890D03*
Y32520D03*
X283385Y21890D03*
Y32520D03*
X273385Y196890D03*
X283385D03*
X273385Y207520D03*
X283385D03*
X273385Y371890D03*
X283385D03*
X273385Y382520D03*
X283385D03*
X273386Y546890D03*
Y557520D03*
X283386Y546890D03*
Y557520D03*
X273386Y721890D03*
Y732520D03*
X283386Y721890D03*
Y732520D03*
X273385Y896890D03*
X283385D03*
X273385Y907520D03*
X283385D03*
X273385Y1071890D03*
X283385D03*
X273385Y1082520D03*
X283385D03*
X273385Y1246890D03*
Y1257520D03*
X283385Y1246890D03*
Y1257520D03*
X273385Y1421890D03*
Y1432520D03*
X283385Y1421890D03*
Y1432520D03*
X273385Y1596890D03*
X283385D03*
X273385Y1607520D03*
X283385D03*
X273385Y1771890D03*
X283385D03*
X273385Y1782520D03*
X283385D03*
X273385Y1946890D03*
Y1957520D03*
X283385Y1946890D03*
Y1957520D03*
X293385Y21890D03*
Y32520D03*
X303385Y21890D03*
Y32520D03*
X313385D03*
Y21890D03*
X293385Y196890D03*
X303385D03*
X313385D03*
X293385Y207520D03*
X303385D03*
X313385D03*
X293385Y371890D03*
X303385D03*
X313385D03*
X293385Y382520D03*
X303385D03*
X313385D03*
X293386Y546890D03*
Y557520D03*
X303386Y546890D03*
Y557520D03*
X313386D03*
Y546890D03*
X293386Y721890D03*
Y732520D03*
X303386Y721890D03*
Y732520D03*
X313386D03*
Y721890D03*
X293385Y896890D03*
X303385D03*
X313385D03*
X293385Y907520D03*
X303385D03*
X313385D03*
X293385Y1071890D03*
X303385D03*
X313385D03*
X293385Y1082520D03*
X303385D03*
X313385D03*
X293385Y1246890D03*
Y1257520D03*
X303385Y1246890D03*
Y1257520D03*
X313385D03*
Y1246890D03*
X293385Y1421890D03*
Y1432520D03*
X303385Y1421890D03*
Y1432520D03*
X313385D03*
Y1421890D03*
X293385Y1596890D03*
X303385D03*
X313385D03*
X293385Y1607520D03*
X303385D03*
X313385D03*
X293385Y1771890D03*
X303385D03*
X313385D03*
X293385Y1782520D03*
X303385D03*
X313385D03*
X293385Y1946890D03*
Y1957520D03*
X303385Y1946890D03*
Y1957520D03*
X313385D03*
Y1946890D03*
X337165Y24705D03*
X323385Y32520D03*
Y21890D03*
X337165Y34705D03*
Y199705D03*
X323385Y196890D03*
X337165Y209705D03*
X323385Y207520D03*
Y371890D03*
X337165Y374705D03*
Y384705D03*
X323385Y382520D03*
X337166Y549705D03*
Y559705D03*
X323386Y557520D03*
Y546890D03*
X337166Y724705D03*
X323386Y732520D03*
Y721890D03*
X337166Y734705D03*
X337165Y899705D03*
X323385Y896890D03*
X337165Y909705D03*
X323385Y907520D03*
Y1071890D03*
X337165Y1074705D03*
Y1084705D03*
X323385Y1082520D03*
X337165Y1249705D03*
Y1259705D03*
X323385Y1257520D03*
Y1246890D03*
X337165Y1424705D03*
Y1434705D03*
X323385Y1432520D03*
Y1421890D03*
X337165Y1599705D03*
X323385Y1596890D03*
X337165Y1609705D03*
X323385Y1607520D03*
Y1771890D03*
X337165Y1774705D03*
Y1784705D03*
X323385Y1782520D03*
X337165Y1949705D03*
Y1959705D03*
X323385Y1957520D03*
Y1946890D03*
X342165Y19705D03*
Y29705D03*
X347165Y24705D03*
X352165Y19705D03*
Y29705D03*
X357165Y24705D03*
X362165Y19705D03*
Y29705D03*
X347165Y34705D03*
X357165D03*
X342165Y194705D03*
X347165Y199705D03*
X352165Y194705D03*
X357165Y199705D03*
X362165Y194705D03*
X342165Y204705D03*
X347165Y209705D03*
X352165Y204705D03*
X357165Y209705D03*
X362165Y204705D03*
X342165Y369705D03*
X352165D03*
X362165D03*
X342165Y379705D03*
X347165Y374705D03*
Y384705D03*
X352165Y379705D03*
X357165Y374705D03*
Y384705D03*
X362165Y379705D03*
X342166Y544705D03*
Y554705D03*
X347166Y549705D03*
Y559705D03*
X352166Y544705D03*
Y554705D03*
X357166Y549705D03*
Y559705D03*
X362166Y544705D03*
Y554705D03*
X342166Y719705D03*
Y729705D03*
X347166Y724705D03*
X352166Y719705D03*
Y729705D03*
X357166Y724705D03*
X362166Y719705D03*
Y729705D03*
X347166Y734705D03*
X357166D03*
X342165Y894705D03*
X347165Y899705D03*
X352165Y894705D03*
X357165Y899705D03*
X362165Y894705D03*
X342165Y904705D03*
X347165Y909705D03*
X352165Y904705D03*
X357165Y909705D03*
X362165Y904705D03*
X342165Y1069705D03*
X352165D03*
X362165D03*
X342165Y1079705D03*
X347165Y1074705D03*
Y1084705D03*
X352165Y1079705D03*
X357165Y1074705D03*
Y1084705D03*
X362165Y1079705D03*
X342165Y1244705D03*
Y1254705D03*
X347165Y1249705D03*
Y1259705D03*
X352165Y1244705D03*
Y1254705D03*
X357165Y1249705D03*
Y1259705D03*
X362165Y1244705D03*
Y1254705D03*
X342165Y1419705D03*
Y1429705D03*
X347165Y1424705D03*
Y1434705D03*
X352165Y1419705D03*
Y1429705D03*
X357165Y1424705D03*
Y1434705D03*
X362165Y1419705D03*
Y1429705D03*
X342165Y1594705D03*
X347165Y1599705D03*
X352165Y1594705D03*
X357165Y1599705D03*
X362165Y1594705D03*
X342165Y1604705D03*
X347165Y1609705D03*
X352165Y1604705D03*
X357165Y1609705D03*
X362165Y1604705D03*
X342165Y1769705D03*
X352165D03*
X362165D03*
X342165Y1779705D03*
X347165Y1774705D03*
Y1784705D03*
X352165Y1779705D03*
X357165Y1774705D03*
Y1784705D03*
X362165Y1779705D03*
X342165Y1944705D03*
Y1954705D03*
X347165Y1949705D03*
Y1959705D03*
X352165Y1944705D03*
Y1954705D03*
X357165Y1949705D03*
Y1959705D03*
X362165Y1944705D03*
Y1954705D03*
M02*
